FILE_TYPE = MACRO_DRAWING;
SET COLOR_WIRE YELLOW;
SET COLOR_PROP ORANGE;
SET COLOR_DOT WHITE;
SET COLOR_ARC YELLOW;
SET COLOR_BODY GREEN;
SET COLOR_NOTE PURPLE;
SET PROP_DISPLAY VALUE;
SET PAGE_NUMBER P23;
FORCEADD GENOA_SP5..13
(-4775 5075);
FORCEPROP 1 LAST LOCATION U25
J 0
(-5870 6331);
DISPLAY 0.489362 (-5870 6331);
PAINT SKYBLUE (-5870 6331);
FORCEPROP 0 LAST $SEC 13
J 0
(-5850 6375);
DISPLAY 0.680851 (-5850 6375);
PAINT MONO (-5850 6375);
DISPLAY INVISIBLE (-5850 6375);
FORCEPROP 0 LAST CDS_SEC 13
J 0
(-5875 6275);
DISPLAY 1.021277 (-5875 6275);
DISPLAY INVISIBLE (-5875 6275);
FORCEPROP 0 LASTPIN (-6025 5775) $PN AE23
J 2
(-6035 5785);
DISPLAY 0.489362 (-6035 5785);
PAINT MONO (-6035 5785);
FORCEPROP 0 LASTPIN (-6025 5675) $PN AC23
J 2
(-6035 5685);
DISPLAY 0.489362 (-6035 5685);
PAINT MONO (-6035 5685);
FORCEPROP 0 LASTPIN (-6025 5575) $PN AG23
J 2
(-6035 5585);
DISPLAY 0.489362 (-6035 5585);
PAINT MONO (-6035 5585);
FORCEPROP 0 LASTPIN (-6025 5475) $PN AE26
J 2
(-6035 5485);
DISPLAY 0.489362 (-6035 5485);
PAINT MONO (-6035 5485);
FORCEPROP 0 LASTPIN (-6025 5375) $PN AC26
J 2
(-6035 5385);
DISPLAY 0.489362 (-6035 5385);
PAINT MONO (-6035 5385);
FORCEPROP 0 LASTPIN (-6025 5275) $PN AG26
J 2
(-6035 5285);
DISPLAY 0.489362 (-6035 5285);
PAINT MONO (-6035 5285);
FORCEPROP 0 LASTPIN (-6025 5175) $PN AE29
J 2
(-6035 5185);
DISPLAY 0.489362 (-6035 5185);
PAINT MONO (-6035 5185);
FORCEPROP 0 LASTPIN (-6025 5075) $PN AC29
J 2
(-6035 5085);
DISPLAY 0.489362 (-6035 5085);
PAINT MONO (-6035 5085);
FORCEPROP 0 LASTPIN (-6025 4975) $PN AG29
J 2
(-6035 4985);
DISPLAY 0.489362 (-6035 4985);
PAINT MONO (-6035 4985);
FORCEPROP 0 LASTPIN (-6025 4875) $PN AE32
J 2
(-6035 4885);
DISPLAY 0.489362 (-6035 4885);
PAINT MONO (-6035 4885);
FORCEPROP 0 LASTPIN (-6025 4775) $PN AC32
J 2
(-6035 4785);
DISPLAY 0.489362 (-6035 4785);
PAINT MONO (-6035 4785);
FORCEPROP 0 LASTPIN (-6025 4675) $PN AA32
J 2
(-6035 4685);
DISPLAY 0.489362 (-6035 4685);
PAINT MONO (-6035 4685);
FORCEPROP 0 LASTPIN (-6025 4575) $PN AG32
J 2
(-6035 4585);
DISPLAY 0.489362 (-6035 4585);
PAINT MONO (-6035 4585);
FORCEPROP 0 LASTPIN (-6025 4475) $PN AB35
J 2
(-6035 4485);
DISPLAY 0.489362 (-6035 4485);
PAINT MONO (-6035 4485);
FORCEPROP 0 LASTPIN (-6025 4375) $PN AD35
J 2
(-6035 4385);
DISPLAY 0.489362 (-6035 4385);
PAINT MONO (-6035 4385);
FORCEPROP 0 LASTPIN (-6025 4275) $PN AF35
J 2
(-6035 4285);
DISPLAY 0.489362 (-6035 4285);
PAINT MONO (-6035 4285);
FORCEPROP 0 LASTPIN (-6025 5825) $PN AE24
J 2
(-6035 5835);
DISPLAY 0.489362 (-6035 5835);
PAINT MONO (-6035 5835);
FORCEPROP 0 LASTPIN (-6025 5725) $PN AC24
J 2
(-6035 5735);
DISPLAY 0.489362 (-6035 5735);
PAINT MONO (-6035 5735);
FORCEPROP 0 LASTPIN (-6025 5625) $PN AG24
J 2
(-6035 5635);
DISPLAY 0.489362 (-6035 5635);
PAINT MONO (-6035 5635);
FORCEPROP 0 LASTPIN (-6025 5525) $PN AE27
J 2
(-6035 5535);
DISPLAY 0.489362 (-6035 5535);
PAINT MONO (-6035 5535);
FORCEPROP 0 LASTPIN (-6025 5425) $PN AC27
J 2
(-6035 5435);
DISPLAY 0.489362 (-6035 5435);
PAINT MONO (-6035 5435);
FORCEPROP 0 LASTPIN (-6025 5325) $PN AG27
J 2
(-6035 5335);
DISPLAY 0.489362 (-6035 5335);
PAINT MONO (-6035 5335);
FORCEPROP 0 LASTPIN (-6025 5225) $PN AE30
J 2
(-6035 5235);
DISPLAY 0.489362 (-6035 5235);
PAINT MONO (-6035 5235);
FORCEPROP 0 LASTPIN (-6025 5125) $PN AC30
J 2
(-6035 5135);
DISPLAY 0.489362 (-6035 5135);
PAINT MONO (-6035 5135);
FORCEPROP 0 LASTPIN (-6025 5025) $PN AG30
J 2
(-6035 5035);
DISPLAY 0.489362 (-6035 5035);
PAINT MONO (-6035 5035);
FORCEPROP 0 LASTPIN (-6025 4925) $PN AE33
J 2
(-6035 4935);
DISPLAY 0.489362 (-6035 4935);
PAINT MONO (-6035 4935);
FORCEPROP 0 LASTPIN (-6025 4825) $PN AC33
J 2
(-6035 4835);
DISPLAY 0.489362 (-6035 4835);
PAINT MONO (-6035 4835);
FORCEPROP 0 LASTPIN (-6025 4725) $PN AA33
J 2
(-6035 4735);
DISPLAY 0.489362 (-6035 4735);
PAINT MONO (-6035 4735);
FORCEPROP 0 LASTPIN (-6025 4625) $PN AG33
J 2
(-6035 4635);
DISPLAY 0.489362 (-6035 4635);
PAINT MONO (-6035 4635);
FORCEPROP 0 LASTPIN (-6025 4525) $PN AB36
J 2
(-6035 4535);
DISPLAY 0.489362 (-6035 4535);
PAINT MONO (-6035 4535);
FORCEPROP 0 LASTPIN (-6025 4425) $PN AD36
J 2
(-6035 4435);
DISPLAY 0.489362 (-6035 4435);
PAINT MONO (-6035 4435);
FORCEPROP 0 LASTPIN (-6025 4325) $PN AF36
J 2
(-6035 4335);
DISPLAY 0.489362 (-6035 4335);
PAINT MONO (-6035 4335);
FORCEPROP 0 LASTPIN (-3525 5775) $PN N24
J 0
(-3515 5785);
DISPLAY 0.489362 (-3515 5785);
PAINT MONO (-3515 5785);
FORCEPROP 0 LASTPIN (-3525 5675) $PN J24
J 0
(-3515 5685);
DISPLAY 0.489362 (-3515 5685);
PAINT MONO (-3515 5685);
FORCEPROP 0 LASTPIN (-3525 5575) $PN G24
J 0
(-3515 5585);
DISPLAY 0.489362 (-3515 5585);
PAINT MONO (-3515 5585);
FORCEPROP 0 LASTPIN (-3525 5475) $PN L24
J 0
(-3515 5485);
DISPLAY 0.489362 (-3515 5485);
PAINT MONO (-3515 5485);
FORCEPROP 0 LASTPIN (-3525 5375) $PN J27
J 0
(-3515 5385);
DISPLAY 0.489362 (-3515 5385);
PAINT MONO (-3515 5385);
FORCEPROP 0 LASTPIN (-3525 5275) $PN G27
J 0
(-3515 5285);
DISPLAY 0.489362 (-3515 5285);
PAINT MONO (-3515 5285);
FORCEPROP 0 LASTPIN (-3525 5175) $PN L27
J 0
(-3515 5185);
DISPLAY 0.489362 (-3515 5185);
PAINT MONO (-3515 5185);
FORCEPROP 0 LASTPIN (-3525 5075) $PN J30
J 0
(-3515 5085);
DISPLAY 0.489362 (-3515 5085);
PAINT MONO (-3515 5085);
FORCEPROP 0 LASTPIN (-3525 4975) $PN G30
J 0
(-3515 4985);
DISPLAY 0.489362 (-3515 4985);
PAINT MONO (-3515 4985);
FORCEPROP 0 LASTPIN (-3525 4875) $PN L30
J 0
(-3515 4885);
DISPLAY 0.489362 (-3515 4885);
PAINT MONO (-3515 4885);
FORCEPROP 0 LASTPIN (-3525 4775) $PN J33
J 0
(-3515 4785);
DISPLAY 0.489362 (-3515 4785);
PAINT MONO (-3515 4785);
FORCEPROP 0 LASTPIN (-3525 4675) $PN G33
J 0
(-3515 4685);
DISPLAY 0.489362 (-3515 4685);
PAINT MONO (-3515 4685);
FORCEPROP 0 LASTPIN (-3525 4575) $PN L33
J 0
(-3515 4585);
DISPLAY 0.489362 (-3515 4585);
PAINT MONO (-3515 4585);
FORCEPROP 0 LASTPIN (-3525 4475) $PN H36
J 0
(-3515 4485);
DISPLAY 0.489362 (-3515 4485);
PAINT MONO (-3515 4485);
FORCEPROP 0 LASTPIN (-3525 4375) $PN K36
J 0
(-3515 4385);
DISPLAY 0.489362 (-3515 4385);
PAINT MONO (-3515 4385);
FORCEPROP 0 LASTPIN (-3525 4275) $PN M36
J 0
(-3515 4285);
DISPLAY 0.489362 (-3515 4285);
PAINT MONO (-3515 4285);
FORCEPROP 0 LASTPIN (-3525 5825) $PN N23
J 0
(-3515 5835);
DISPLAY 0.489362 (-3515 5835);
PAINT MONO (-3515 5835);
FORCEPROP 0 LASTPIN (-3525 5725) $PN J23
J 0
(-3515 5735);
DISPLAY 0.489362 (-3515 5735);
PAINT MONO (-3515 5735);
FORCEPROP 0 LASTPIN (-3525 5625) $PN G23
J 0
(-3515 5635);
DISPLAY 0.489362 (-3515 5635);
PAINT MONO (-3515 5635);
FORCEPROP 0 LASTPIN (-3525 5525) $PN L23
J 0
(-3515 5535);
DISPLAY 0.489362 (-3515 5535);
PAINT MONO (-3515 5535);
FORCEPROP 0 LASTPIN (-3525 5425) $PN J26
J 0
(-3515 5435);
DISPLAY 0.489362 (-3515 5435);
PAINT MONO (-3515 5435);
FORCEPROP 0 LASTPIN (-3525 5325) $PN G26
J 0
(-3515 5335);
DISPLAY 0.489362 (-3515 5335);
PAINT MONO (-3515 5335);
FORCEPROP 0 LASTPIN (-3525 5225) $PN L26
J 0
(-3515 5235);
DISPLAY 0.489362 (-3515 5235);
PAINT MONO (-3515 5235);
FORCEPROP 0 LASTPIN (-3525 5125) $PN J29
J 0
(-3515 5135);
DISPLAY 0.489362 (-3515 5135);
PAINT MONO (-3515 5135);
FORCEPROP 0 LASTPIN (-3525 5025) $PN G29
J 0
(-3515 5035);
DISPLAY 0.489362 (-3515 5035);
PAINT MONO (-3515 5035);
FORCEPROP 0 LASTPIN (-3525 4925) $PN L29
J 0
(-3515 4935);
DISPLAY 0.489362 (-3515 4935);
PAINT MONO (-3515 4935);
FORCEPROP 0 LASTPIN (-3525 4825) $PN J32
J 0
(-3515 4835);
DISPLAY 0.489362 (-3515 4835);
PAINT MONO (-3515 4835);
FORCEPROP 0 LASTPIN (-3525 4725) $PN G32
J 0
(-3515 4735);
DISPLAY 0.489362 (-3515 4735);
PAINT MONO (-3515 4735);
FORCEPROP 0 LASTPIN (-3525 4625) $PN L32
J 0
(-3515 4635);
DISPLAY 0.489362 (-3515 4635);
PAINT MONO (-3515 4635);
FORCEPROP 0 LASTPIN (-3525 4525) $PN H35
J 0
(-3515 4535);
DISPLAY 0.489362 (-3515 4535);
PAINT MONO (-3515 4535);
FORCEPROP 0 LASTPIN (-3525 4425) $PN K35
J 0
(-3515 4435);
DISPLAY 0.489362 (-3515 4435);
PAINT MONO (-3515 4435);
FORCEPROP 0 LASTPIN (-3525 4325) $PN M35
J 0
(-3515 4335);
DISPLAY 0.489362 (-3515 4335);
PAINT MONO (-3515 4335);
FORCEPROP 2 LAST PART_TYPE SMLF
J 0
(-5875 6225);
DISPLAY 1.021277 (-5875 6225);
FORCEPROP 2 LAST VALUE SOCKET6096_13568-001
J 0
(-5875 6125);
DISPLAY 0.489362 (-5875 6125);
PAINT SKYBLUE (-5875 6125);
FORCEPROP 1 LAST MATERIAL IO
J 0
(-5870 6057);
DISPLAY 0.489362 (-5870 6057);
PAINT SKYBLUE (-5870 6057);
FORCEPROP 2 LAST CDS_LIB pure_quanta
J 0
(-4775 5075);
DISPLAY INVISIBLE (-4775 5075);
FORCEPROP 1 LAST NEEDS_NO_SIZE TRUE
J 0
(-4775 5075);
DISPLAY 0.723404 (-4775 5075);
PAINT GREEN (-4775 5075);
DISPLAY INVISIBLE (-4775 5075);
FORCEPROP 1 LAST CDS_LMAN_SYM_OUTLINE -1100,950,1100,-950
J 0
(-4775 5075);
DISPLAY 0.468085 (-4775 5075);
PAINT GREEN (-4775 5075);
DISPLAY INVISIBLE (-4775 5075);
FORCEPROP 1 LAST PATH I215
J 0
(-4775 5075);
DISPLAY 0.723404 (-4775 5075);
PAINT GREEN (-4775 5075);
DISPLAY INVISIBLE (-4775 5075);
FORCEPROP 1 LAST PART_NUMBER DGA^6000030
J 0
(-5870 6184);
DISPLAY 0.489362 (-5870 6184);
PAINT SKYBLUE (-5870 6184);
DISPLAY INVISIBLE (-5870 6184);
FORCEADD GENOA_SP5..14
(-4750 2200);
FORCEPROP 1 LAST LOCATION U25
J 0
(-5845 3456);
DISPLAY 0.489362 (-5845 3456);
PAINT SKYBLUE (-5845 3456);
FORCEPROP 0 LAST $SEC 14
J 0
(-5825 3500);
DISPLAY 0.680851 (-5825 3500);
PAINT MONO (-5825 3500);
DISPLAY INVISIBLE (-5825 3500);
FORCEPROP 0 LAST CDS_SEC 14
J 0
(-5850 3400);
DISPLAY 1.021277 (-5850 3400);
DISPLAY INVISIBLE (-5850 3400);
FORCEPROP 0 LASTPIN (-6000 2900) $PN AL23
J 2
(-6010 2910);
DISPLAY 0.489362 (-6010 2910);
PAINT MONO (-6010 2910);
FORCEPROP 0 LASTPIN (-6000 2800) $PN AJ23
J 2
(-6010 2810);
DISPLAY 0.489362 (-6010 2810);
PAINT MONO (-6010 2810);
FORCEPROP 0 LASTPIN (-6000 2700) $PN AN23
J 2
(-6010 2710);
DISPLAY 0.489362 (-6010 2710);
PAINT MONO (-6010 2710);
FORCEPROP 0 LASTPIN (-6000 2600) $PN AL26
J 2
(-6010 2610);
DISPLAY 0.489362 (-6010 2610);
PAINT MONO (-6010 2610);
FORCEPROP 0 LASTPIN (-6000 2500) $PN AJ26
J 2
(-6010 2510);
DISPLAY 0.489362 (-6010 2510);
PAINT MONO (-6010 2510);
FORCEPROP 0 LASTPIN (-6000 2400) $PN AN26
J 2
(-6010 2410);
DISPLAY 0.489362 (-6010 2410);
PAINT MONO (-6010 2410);
FORCEPROP 0 LASTPIN (-6000 2300) $PN AL29
J 2
(-6010 2310);
DISPLAY 0.489362 (-6010 2310);
PAINT MONO (-6010 2310);
FORCEPROP 0 LASTPIN (-6000 2200) $PN AJ29
J 2
(-6010 2210);
DISPLAY 0.489362 (-6010 2210);
PAINT MONO (-6010 2210);
FORCEPROP 0 LASTPIN (-6000 2100) $PN AN29
J 2
(-6010 2110);
DISPLAY 0.489362 (-6010 2110);
PAINT MONO (-6010 2110);
FORCEPROP 0 LASTPIN (-6000 2000) $PN AL32
J 2
(-6010 2010);
DISPLAY 0.489362 (-6010 2010);
PAINT MONO (-6010 2010);
FORCEPROP 0 LASTPIN (-6000 1900) $PN AJ32
J 2
(-6010 1910);
DISPLAY 0.489362 (-6010 1910);
PAINT MONO (-6010 1910);
FORCEPROP 0 LASTPIN (-6000 1800) $PN AN32
J 2
(-6010 1810);
DISPLAY 0.489362 (-6010 1810);
PAINT MONO (-6010 1810);
FORCEPROP 0 LASTPIN (-6000 1700) $PN AK35
J 2
(-6010 1710);
DISPLAY 0.489362 (-6010 1710);
PAINT MONO (-6010 1710);
FORCEPROP 0 LASTPIN (-6000 1600) $PN AH35
J 2
(-6010 1610);
DISPLAY 0.489362 (-6010 1610);
PAINT MONO (-6010 1610);
FORCEPROP 0 LASTPIN (-6000 1500) $PN AM35
J 2
(-6010 1510);
DISPLAY 0.489362 (-6010 1510);
PAINT MONO (-6010 1510);
FORCEPROP 0 LASTPIN (-6000 1400) $PN AP35
J 2
(-6010 1410);
DISPLAY 0.489362 (-6010 1410);
PAINT MONO (-6010 1410);
FORCEPROP 0 LASTPIN (-6000 2950) $PN AL24
J 2
(-6010 2960);
DISPLAY 0.489362 (-6010 2960);
PAINT MONO (-6010 2960);
FORCEPROP 0 LASTPIN (-6000 2850) $PN AJ24
J 2
(-6010 2860);
DISPLAY 0.489362 (-6010 2860);
PAINT MONO (-6010 2860);
FORCEPROP 0 LASTPIN (-6000 2750) $PN AN24
J 2
(-6010 2760);
DISPLAY 0.489362 (-6010 2760);
PAINT MONO (-6010 2760);
FORCEPROP 0 LASTPIN (-6000 2650) $PN AL27
J 2
(-6010 2660);
DISPLAY 0.489362 (-6010 2660);
PAINT MONO (-6010 2660);
FORCEPROP 0 LASTPIN (-6000 2550) $PN AJ27
J 2
(-6010 2560);
DISPLAY 0.489362 (-6010 2560);
PAINT MONO (-6010 2560);
FORCEPROP 0 LASTPIN (-6000 2450) $PN AN27
J 2
(-6010 2460);
DISPLAY 0.489362 (-6010 2460);
PAINT MONO (-6010 2460);
FORCEPROP 0 LASTPIN (-6000 2350) $PN AL30
J 2
(-6010 2360);
DISPLAY 0.489362 (-6010 2360);
PAINT MONO (-6010 2360);
FORCEPROP 0 LASTPIN (-6000 2250) $PN AJ30
J 2
(-6010 2260);
DISPLAY 0.489362 (-6010 2260);
PAINT MONO (-6010 2260);
FORCEPROP 0 LASTPIN (-6000 2150) $PN AN30
J 2
(-6010 2160);
DISPLAY 0.489362 (-6010 2160);
PAINT MONO (-6010 2160);
FORCEPROP 0 LASTPIN (-6000 2050) $PN AL33
J 2
(-6010 2060);
DISPLAY 0.489362 (-6010 2060);
PAINT MONO (-6010 2060);
FORCEPROP 0 LASTPIN (-6000 1950) $PN AJ33
J 2
(-6010 1960);
DISPLAY 0.489362 (-6010 1960);
PAINT MONO (-6010 1960);
FORCEPROP 0 LASTPIN (-6000 1850) $PN AN33
J 2
(-6010 1860);
DISPLAY 0.489362 (-6010 1860);
PAINT MONO (-6010 1860);
FORCEPROP 0 LASTPIN (-6000 1750) $PN AK36
J 2
(-6010 1760);
DISPLAY 0.489362 (-6010 1760);
PAINT MONO (-6010 1760);
FORCEPROP 0 LASTPIN (-6000 1650) $PN AH36
J 2
(-6010 1660);
DISPLAY 0.489362 (-6010 1660);
PAINT MONO (-6010 1660);
FORCEPROP 0 LASTPIN (-6000 1550) $PN AM36
J 2
(-6010 1560);
DISPLAY 0.489362 (-6010 1560);
PAINT MONO (-6010 1560);
FORCEPROP 0 LASTPIN (-6000 1450) $PN AP36
J 2
(-6010 1460);
DISPLAY 0.489362 (-6010 1460);
PAINT MONO (-6010 1460);
FORCEPROP 0 LASTPIN (-3500 2900) $PN U24
J 0
(-3490 2910);
DISPLAY 0.489362 (-3490 2910);
PAINT MONO (-3490 2910);
FORCEPROP 0 LASTPIN (-3500 2800) $PN R24
J 0
(-3490 2810);
DISPLAY 0.489362 (-3490 2810);
PAINT MONO (-3490 2810);
FORCEPROP 0 LASTPIN (-3500 2700) $PN W24
J 0
(-3490 2710);
DISPLAY 0.489362 (-3490 2710);
PAINT MONO (-3490 2710);
FORCEPROP 0 LASTPIN (-3500 2600) $PN U27
J 0
(-3490 2610);
DISPLAY 0.489362 (-3490 2610);
PAINT MONO (-3490 2610);
FORCEPROP 0 LASTPIN (-3500 2500) $PN R27
J 0
(-3490 2510);
DISPLAY 0.489362 (-3490 2510);
PAINT MONO (-3490 2510);
FORCEPROP 0 LASTPIN (-3500 2400) $PN N27
J 0
(-3490 2410);
DISPLAY 0.489362 (-3490 2410);
PAINT MONO (-3490 2410);
FORCEPROP 0 LASTPIN (-3500 2300) $PN W27
J 0
(-3490 2310);
DISPLAY 0.489362 (-3490 2310);
PAINT MONO (-3490 2310);
FORCEPROP 0 LASTPIN (-3500 2200) $PN R30
J 0
(-3490 2210);
DISPLAY 0.489362 (-3490 2210);
PAINT MONO (-3490 2210);
FORCEPROP 0 LASTPIN (-3500 2100) $PN N30
J 0
(-3490 2110);
DISPLAY 0.489362 (-3490 2110);
PAINT MONO (-3490 2110);
FORCEPROP 0 LASTPIN (-3500 2000) $PN U30
J 0
(-3490 2010);
DISPLAY 0.489362 (-3490 2010);
PAINT MONO (-3490 2010);
FORCEPROP 0 LASTPIN (-3500 1900) $PN R33
J 0
(-3490 1910);
DISPLAY 0.489362 (-3490 1910);
PAINT MONO (-3490 1910);
FORCEPROP 0 LASTPIN (-3500 1800) $PN N33
J 0
(-3490 1810);
DISPLAY 0.489362 (-3490 1810);
PAINT MONO (-3490 1810);
FORCEPROP 0 LASTPIN (-3500 1700) $PN U33
J 0
(-3490 1710);
DISPLAY 0.489362 (-3490 1710);
PAINT MONO (-3490 1710);
FORCEPROP 0 LASTPIN (-3500 1600) $PN P36
J 0
(-3490 1610);
DISPLAY 0.489362 (-3490 1610);
PAINT MONO (-3490 1610);
FORCEPROP 0 LASTPIN (-3500 1500) $PN T36
J 0
(-3490 1510);
DISPLAY 0.489362 (-3490 1510);
PAINT MONO (-3490 1510);
FORCEPROP 0 LASTPIN (-3500 1400) $PN V36
J 0
(-3490 1410);
DISPLAY 0.489362 (-3490 1410);
PAINT MONO (-3490 1410);
FORCEPROP 0 LASTPIN (-3500 2950) $PN U23
J 0
(-3490 2960);
DISPLAY 0.489362 (-3490 2960);
PAINT MONO (-3490 2960);
FORCEPROP 0 LASTPIN (-3500 2850) $PN R23
J 0
(-3490 2860);
DISPLAY 0.489362 (-3490 2860);
PAINT MONO (-3490 2860);
FORCEPROP 0 LASTPIN (-3500 2750) $PN W23
J 0
(-3490 2760);
DISPLAY 0.489362 (-3490 2760);
PAINT MONO (-3490 2760);
FORCEPROP 0 LASTPIN (-3500 2650) $PN U26
J 0
(-3490 2660);
DISPLAY 0.489362 (-3490 2660);
PAINT MONO (-3490 2660);
FORCEPROP 0 LASTPIN (-3500 2550) $PN R26
J 0
(-3490 2560);
DISPLAY 0.489362 (-3490 2560);
PAINT MONO (-3490 2560);
FORCEPROP 0 LASTPIN (-3500 2450) $PN N26
J 0
(-3490 2460);
DISPLAY 0.489362 (-3490 2460);
PAINT MONO (-3490 2460);
FORCEPROP 0 LASTPIN (-3500 2350) $PN W26
J 0
(-3490 2360);
DISPLAY 0.489362 (-3490 2360);
PAINT MONO (-3490 2360);
FORCEPROP 0 LASTPIN (-3500 2250) $PN R29
J 0
(-3490 2260);
DISPLAY 0.489362 (-3490 2260);
PAINT MONO (-3490 2260);
FORCEPROP 0 LASTPIN (-3500 2150) $PN N29
J 0
(-3490 2160);
DISPLAY 0.489362 (-3490 2160);
PAINT MONO (-3490 2160);
FORCEPROP 0 LASTPIN (-3500 2050) $PN U29
J 0
(-3490 2060);
DISPLAY 0.489362 (-3490 2060);
PAINT MONO (-3490 2060);
FORCEPROP 0 LASTPIN (-3500 1950) $PN R32
J 0
(-3490 1960);
DISPLAY 0.489362 (-3490 1960);
PAINT MONO (-3490 1960);
FORCEPROP 0 LASTPIN (-3500 1850) $PN N32
J 0
(-3490 1860);
DISPLAY 0.489362 (-3490 1860);
PAINT MONO (-3490 1860);
FORCEPROP 0 LASTPIN (-3500 1750) $PN U32
J 0
(-3490 1760);
DISPLAY 0.489362 (-3490 1760);
PAINT MONO (-3490 1760);
FORCEPROP 0 LASTPIN (-3500 1650) $PN P35
J 0
(-3490 1660);
DISPLAY 0.489362 (-3490 1660);
PAINT MONO (-3490 1660);
FORCEPROP 0 LASTPIN (-3500 1550) $PN T35
J 0
(-3490 1560);
DISPLAY 0.489362 (-3490 1560);
PAINT MONO (-3490 1560);
FORCEPROP 0 LASTPIN (-3500 1450) $PN V35
J 0
(-3490 1460);
DISPLAY 0.489362 (-3490 1460);
PAINT MONO (-3490 1460);
FORCEPROP 2 LAST PART_TYPE SMLF
J 0
(-5850 3350);
DISPLAY 1.021277 (-5850 3350);
FORCEPROP 1 LAST MATERIAL IO
J 0
(-5845 3182);
DISPLAY 0.489362 (-5845 3182);
PAINT SKYBLUE (-5845 3182);
FORCEPROP 2 LAST VALUE SOCKET6096_13568-001
J 0
(-5850 3250);
DISPLAY 0.489362 (-5850 3250);
PAINT SKYBLUE (-5850 3250);
FORCEPROP 2 LAST CDS_LIB pure_quanta
J 0
(-4750 2200);
DISPLAY INVISIBLE (-4750 2200);
FORCEPROP 1 LAST NEEDS_NO_SIZE TRUE
J 0
(-4750 2200);
DISPLAY 0.723404 (-4750 2200);
PAINT GREEN (-4750 2200);
DISPLAY INVISIBLE (-4750 2200);
FORCEPROP 1 LAST CDS_LMAN_SYM_OUTLINE -1100,950,1100,-950
J 0
(-4750 2200);
DISPLAY 0.468085 (-4750 2200);
PAINT GREEN (-4750 2200);
DISPLAY INVISIBLE (-4750 2200);
FORCEPROP 1 LAST PATH I216
J 0
(-4750 2200);
DISPLAY 0.723404 (-4750 2200);
PAINT GREEN (-4750 2200);
DISPLAY INVISIBLE (-4750 2200);
FORCEPROP 1 LAST PART_NUMBER DGA^6000030
J 0
(-5845 3309);
DISPLAY 0.489362 (-5845 3309);
PAINT SKYBLUE (-5845 3309);
DISPLAY INVISIBLE (-5845 3309);
FORCEADD OFFPAGE..2
(-1825 6050);
FORCEPROP 2 LAST $XR0 49 
J 0
(-1636 6050);
DISPLAY 0.638298 (-1636 6050);
PAINT MONO (-1636 6050);
FORCEPROP 2 LAST CDS_LIB standard
J 0
(-1825 6050);
DISPLAY INVISIBLE (-1825 6050);
FORCEPROP 1 LAST OFFPAGE TRUE
J 0
(-1500 5925);
DISPLAY 0.872340 (-1500 5925);
PAINT GREEN (-1500 5925);
DISPLAY INVISIBLE (-1500 5925);
FORCEPROP 1 LAST COMMENT_BODY TRUE
J 0
(-1870 5955);
DISPLAY 0.872340 (-1870 5955);
PAINT GREEN (-1870 5955);
DISPLAY INVISIBLE (-1870 5955);
FORCEPROP 2 LAST PATH I217
J 0
(-1625 6100);
DISPLAY 1.021277 (-1625 6100);
DISPLAY INVISIBLE (-1625 6100);
FORCEADD OFFPAGE..2
(-1825 6000);
FORCEPROP 2 LAST $XR0 49 
J 0
(-1636 6000);
DISPLAY 0.638298 (-1636 6000);
PAINT MONO (-1636 6000);
FORCEPROP 2 LAST CDS_LIB standard
J 0
(-1825 6000);
DISPLAY INVISIBLE (-1825 6000);
FORCEPROP 1 LAST OFFPAGE TRUE
J 0
(-1500 5875);
DISPLAY 0.872340 (-1500 5875);
PAINT GREEN (-1500 5875);
DISPLAY INVISIBLE (-1500 5875);
FORCEPROP 1 LAST COMMENT_BODY TRUE
J 0
(-1870 5905);
DISPLAY 0.872340 (-1870 5905);
PAINT GREEN (-1870 5905);
DISPLAY INVISIBLE (-1870 5905);
FORCEPROP 2 LAST PATH I218
J 0
(-1625 6050);
DISPLAY 1.021277 (-1625 6050);
DISPLAY INVISIBLE (-1625 6050);
FORCEADD TAP..6
R 2
(-2950 5775);
FORCEPROP 3 LASTPIN (-3000 5775) SIG_NAME GMI_CPU0_G2_CPU1_G0_TX_DN<0>
J 0
(-2990 5785);
DISPLAY 0.659574 (-2990 5785);
PAINT MONO (-2990 5785);
DISPLAY INVISIBLE (-2990 5785);
FORCEPROP 1 LASTPIN (-3000 5775) BN 0
J 2
(-2948 5783);
DISPLAY 0.489362 (-2948 5783);
PAINT MONO (-2948 5783);
FORCEPROP 2 LAST BOM_COST IO_SLOT
J 0
(-3450 5875);
DISPLAY 0.829787 (-3450 5875);
DISPLAY INVISIBLE (-3450 5875);
FORCEPROP 2 LAST CDS_LIB mstr_standard
J 0
(-2950 5775);
DISPLAY INVISIBLE (-2950 5775);
FORCEPROP 2 LAST ROOM RISER1
J 0
(-3450 5825);
DISPLAY 0.829787 (-3450 5825);
PAINT RED (-3450 5825);
DISPLAY INVISIBLE (-3450 5825);
FORCEPROP 1 LAST BODY_TYPE PLUMBING
J 2
(-2950 5725);
DISPLAY 0.702128 (-2950 5725);
PAINT GREEN (-2950 5725);
DISPLAY INVISIBLE (-2950 5725);
FORCEPROP 1 LAST HDL_TAP TRUE
J 2
(-3275 5650);
DISPLAY 0.702128 (-3275 5650);
PAINT GREEN (-3275 5650);
DISPLAY INVISIBLE (-3275 5650);
FORCEPROP 1 LAST PATH I219
J 2
(-2948 5775);
DISPLAY 0.872340 (-2948 5775);
PAINT GREEN (-2948 5775);
DISPLAY INVISIBLE (-2948 5775);
FORCEADD TAP..6
R 2
(-2950 5675);
FORCEPROP 3 LASTPIN (-3000 5675) SIG_NAME GMI_CPU0_G2_CPU1_G0_TX_DN<1>
J 0
(-2990 5685);
DISPLAY 0.659574 (-2990 5685);
PAINT MONO (-2990 5685);
DISPLAY INVISIBLE (-2990 5685);
FORCEPROP 1 LASTPIN (-3000 5675) BN 1
J 2
(-2948 5683);
DISPLAY 0.489362 (-2948 5683);
PAINT MONO (-2948 5683);
FORCEPROP 2 LAST CDS_LIB mstr_standard
J 0
(-2950 5675);
DISPLAY INVISIBLE (-2950 5675);
FORCEPROP 2 LAST BOM_COST IO_SLOT
J 0
(-3450 5775);
DISPLAY 0.829787 (-3450 5775);
DISPLAY INVISIBLE (-3450 5775);
FORCEPROP 2 LAST ROOM RISER1
J 0
(-3450 5725);
DISPLAY 0.829787 (-3450 5725);
PAINT RED (-3450 5725);
DISPLAY INVISIBLE (-3450 5725);
FORCEPROP 1 LAST BODY_TYPE PLUMBING
J 2
(-2950 5625);
DISPLAY 0.702128 (-2950 5625);
PAINT GREEN (-2950 5625);
DISPLAY INVISIBLE (-2950 5625);
FORCEPROP 1 LAST HDL_TAP TRUE
J 2
(-3275 5550);
DISPLAY 0.702128 (-3275 5550);
PAINT GREEN (-3275 5550);
DISPLAY INVISIBLE (-3275 5550);
FORCEPROP 1 LAST PATH I220
J 2
(-2948 5675);
DISPLAY 0.872340 (-2948 5675);
PAINT GREEN (-2948 5675);
DISPLAY INVISIBLE (-2948 5675);
FORCEADD TAP..6
R 2
(-3100 5825);
FORCEPROP 3 LASTPIN (-3150 5825) SIG_NAME GMI_CPU0_G2_CPU1_G0_TX_DP<0>
J 0
(-3140 5835);
DISPLAY 0.659574 (-3140 5835);
PAINT MONO (-3140 5835);
DISPLAY INVISIBLE (-3140 5835);
FORCEPROP 1 LASTPIN (-3150 5825) BN 0
J 2
(-3098 5833);
DISPLAY 0.489362 (-3098 5833);
PAINT MONO (-3098 5833);
FORCEPROP 2 LAST CDS_LIB mstr_standard
J 0
(-3100 5825);
DISPLAY INVISIBLE (-3100 5825);
FORCEPROP 2 LAST BOM_COST IO_SLOT
J 0
(-3600 5925);
DISPLAY 0.829787 (-3600 5925);
DISPLAY INVISIBLE (-3600 5925);
FORCEPROP 2 LAST ROOM RISER1
J 0
(-3600 5875);
DISPLAY 0.829787 (-3600 5875);
PAINT RED (-3600 5875);
DISPLAY INVISIBLE (-3600 5875);
FORCEPROP 1 LAST BODY_TYPE PLUMBING
J 2
(-3100 5775);
DISPLAY 0.702128 (-3100 5775);
PAINT GREEN (-3100 5775);
DISPLAY INVISIBLE (-3100 5775);
FORCEPROP 1 LAST HDL_TAP TRUE
J 2
(-3425 5700);
DISPLAY 0.702128 (-3425 5700);
PAINT GREEN (-3425 5700);
DISPLAY INVISIBLE (-3425 5700);
FORCEPROP 1 LAST PATH I221
J 2
(-3098 5825);
DISPLAY 0.872340 (-3098 5825);
PAINT GREEN (-3098 5825);
DISPLAY INVISIBLE (-3098 5825);
FORCEADD TAP..6
R 2
(-3100 5725);
FORCEPROP 3 LASTPIN (-3150 5725) SIG_NAME GMI_CPU0_G2_CPU1_G0_TX_DP<1>
J 0
(-3140 5735);
DISPLAY 0.659574 (-3140 5735);
PAINT MONO (-3140 5735);
DISPLAY INVISIBLE (-3140 5735);
FORCEPROP 1 LASTPIN (-3150 5725) BN 1
J 2
(-3098 5733);
DISPLAY 0.489362 (-3098 5733);
PAINT MONO (-3098 5733);
FORCEPROP 2 LAST CDS_LIB mstr_standard
J 0
(-3100 5725);
DISPLAY INVISIBLE (-3100 5725);
FORCEPROP 2 LAST BOM_COST IO_SLOT
J 0
(-3600 5825);
DISPLAY 0.829787 (-3600 5825);
DISPLAY INVISIBLE (-3600 5825);
FORCEPROP 2 LAST ROOM RISER1
J 0
(-3600 5775);
DISPLAY 0.829787 (-3600 5775);
PAINT RED (-3600 5775);
DISPLAY INVISIBLE (-3600 5775);
FORCEPROP 1 LAST BODY_TYPE PLUMBING
J 2
(-3100 5675);
DISPLAY 0.702128 (-3100 5675);
PAINT GREEN (-3100 5675);
DISPLAY INVISIBLE (-3100 5675);
FORCEPROP 1 LAST HDL_TAP TRUE
J 2
(-3425 5600);
DISPLAY 0.702128 (-3425 5600);
PAINT GREEN (-3425 5600);
DISPLAY INVISIBLE (-3425 5600);
FORCEPROP 1 LAST PATH I222
J 2
(-3098 5725);
DISPLAY 0.872340 (-3098 5725);
PAINT GREEN (-3098 5725);
DISPLAY INVISIBLE (-3098 5725);
FORCEADD TAP..6
R 2
(-2950 5575);
FORCEPROP 3 LASTPIN (-3000 5575) SIG_NAME GMI_CPU0_G2_CPU1_G0_TX_DN<2>
J 0
(-2990 5585);
DISPLAY 0.659574 (-2990 5585);
PAINT MONO (-2990 5585);
DISPLAY INVISIBLE (-2990 5585);
FORCEPROP 1 LASTPIN (-3000 5575) BN 2
J 2
(-2948 5583);
DISPLAY 0.489362 (-2948 5583);
PAINT MONO (-2948 5583);
FORCEPROP 2 LAST CDS_LIB standard
J 0
(-2950 5575);
DISPLAY INVISIBLE (-2950 5575);
FORCEPROP 2 LAST BOM_COST IO_SLOT
J 0
(-3450 5675);
DISPLAY 0.829787 (-3450 5675);
DISPLAY INVISIBLE (-3450 5675);
FORCEPROP 2 LAST ROOM RISER1
J 0
(-3450 5625);
DISPLAY 0.829787 (-3450 5625);
PAINT RED (-3450 5625);
DISPLAY INVISIBLE (-3450 5625);
FORCEPROP 1 LAST BODY_TYPE PLUMBING
J 2
(-2950 5525);
DISPLAY 0.702128 (-2950 5525);
PAINT GREEN (-2950 5525);
DISPLAY INVISIBLE (-2950 5525);
FORCEPROP 1 LAST HDL_TAP TRUE
J 2
(-3275 5450);
DISPLAY 0.702128 (-3275 5450);
PAINT GREEN (-3275 5450);
DISPLAY INVISIBLE (-3275 5450);
FORCEPROP 1 LAST PATH I223
J 2
(-2948 5575);
DISPLAY 0.872340 (-2948 5575);
PAINT GREEN (-2948 5575);
DISPLAY INVISIBLE (-2948 5575);
FORCEADD TAP..6
R 2
(-2950 5475);
FORCEPROP 3 LASTPIN (-3000 5475) SIG_NAME GMI_CPU0_G2_CPU1_G0_TX_DN<3>
J 0
(-2990 5485);
DISPLAY 0.659574 (-2990 5485);
PAINT MONO (-2990 5485);
DISPLAY INVISIBLE (-2990 5485);
FORCEPROP 1 LASTPIN (-3000 5475) BN 3
J 2
(-2948 5483);
DISPLAY 0.489362 (-2948 5483);
PAINT MONO (-2948 5483);
FORCEPROP 2 LAST CDS_LIB standard
J 0
(-2950 5475);
DISPLAY INVISIBLE (-2950 5475);
FORCEPROP 2 LAST BOM_COST IO_SLOT
J 0
(-3450 5575);
DISPLAY 0.829787 (-3450 5575);
DISPLAY INVISIBLE (-3450 5575);
FORCEPROP 2 LAST ROOM RISER1
J 0
(-3450 5525);
DISPLAY 0.829787 (-3450 5525);
PAINT RED (-3450 5525);
DISPLAY INVISIBLE (-3450 5525);
FORCEPROP 1 LAST BODY_TYPE PLUMBING
J 2
(-2950 5425);
DISPLAY 0.702128 (-2950 5425);
PAINT GREEN (-2950 5425);
DISPLAY INVISIBLE (-2950 5425);
FORCEPROP 1 LAST HDL_TAP TRUE
J 2
(-3275 5350);
DISPLAY 0.702128 (-3275 5350);
PAINT GREEN (-3275 5350);
DISPLAY INVISIBLE (-3275 5350);
FORCEPROP 1 LAST PATH I224
J 2
(-2948 5475);
DISPLAY 0.872340 (-2948 5475);
PAINT GREEN (-2948 5475);
DISPLAY INVISIBLE (-2948 5475);
FORCEADD TAP..6
R 2
(-3100 5625);
FORCEPROP 3 LASTPIN (-3150 5625) SIG_NAME GMI_CPU0_G2_CPU1_G0_TX_DP<2>
J 0
(-3140 5635);
DISPLAY 0.659574 (-3140 5635);
PAINT MONO (-3140 5635);
DISPLAY INVISIBLE (-3140 5635);
FORCEPROP 1 LASTPIN (-3150 5625) BN 2
J 2
(-3098 5633);
DISPLAY 0.489362 (-3098 5633);
PAINT MONO (-3098 5633);
FORCEPROP 2 LAST CDS_LIB standard
J 0
(-3100 5625);
DISPLAY INVISIBLE (-3100 5625);
FORCEPROP 2 LAST BOM_COST IO_SLOT
J 0
(-3600 5725);
DISPLAY 0.829787 (-3600 5725);
DISPLAY INVISIBLE (-3600 5725);
FORCEPROP 2 LAST ROOM RISER1
J 0
(-3600 5675);
DISPLAY 0.829787 (-3600 5675);
PAINT RED (-3600 5675);
DISPLAY INVISIBLE (-3600 5675);
FORCEPROP 1 LAST BODY_TYPE PLUMBING
J 2
(-3100 5575);
DISPLAY 0.702128 (-3100 5575);
PAINT GREEN (-3100 5575);
DISPLAY INVISIBLE (-3100 5575);
FORCEPROP 1 LAST HDL_TAP TRUE
J 2
(-3425 5500);
DISPLAY 0.702128 (-3425 5500);
PAINT GREEN (-3425 5500);
DISPLAY INVISIBLE (-3425 5500);
FORCEPROP 1 LAST PATH I225
J 2
(-3098 5625);
DISPLAY 0.872340 (-3098 5625);
PAINT GREEN (-3098 5625);
DISPLAY INVISIBLE (-3098 5625);
FORCEADD TAP..6
R 2
(-3100 5525);
FORCEPROP 3 LASTPIN (-3150 5525) SIG_NAME GMI_CPU0_G2_CPU1_G0_TX_DP<3>
J 0
(-3140 5535);
DISPLAY 0.659574 (-3140 5535);
PAINT MONO (-3140 5535);
DISPLAY INVISIBLE (-3140 5535);
FORCEPROP 1 LASTPIN (-3150 5525) BN 3
J 2
(-3098 5533);
DISPLAY 0.489362 (-3098 5533);
PAINT MONO (-3098 5533);
FORCEPROP 2 LAST CDS_LIB standard
J 0
(-3100 5525);
DISPLAY INVISIBLE (-3100 5525);
FORCEPROP 2 LAST BOM_COST IO_SLOT
J 0
(-3600 5625);
DISPLAY 0.829787 (-3600 5625);
DISPLAY INVISIBLE (-3600 5625);
FORCEPROP 2 LAST ROOM RISER1
J 0
(-3600 5575);
DISPLAY 0.829787 (-3600 5575);
PAINT RED (-3600 5575);
DISPLAY INVISIBLE (-3600 5575);
FORCEPROP 1 LAST BODY_TYPE PLUMBING
J 2
(-3100 5475);
DISPLAY 0.702128 (-3100 5475);
PAINT GREEN (-3100 5475);
DISPLAY INVISIBLE (-3100 5475);
FORCEPROP 1 LAST HDL_TAP TRUE
J 2
(-3425 5400);
DISPLAY 0.702128 (-3425 5400);
PAINT GREEN (-3425 5400);
DISPLAY INVISIBLE (-3425 5400);
FORCEPROP 1 LAST PATH I226
J 2
(-3098 5525);
DISPLAY 0.872340 (-3098 5525);
PAINT GREEN (-3098 5525);
DISPLAY INVISIBLE (-3098 5525);
FORCEADD TAP..6
R 2
(-3100 5425);
FORCEPROP 3 LASTPIN (-3150 5425) SIG_NAME GMI_CPU0_G2_CPU1_G0_TX_DP<4>
J 0
(-3140 5435);
DISPLAY 0.659574 (-3140 5435);
PAINT MONO (-3140 5435);
DISPLAY INVISIBLE (-3140 5435);
FORCEPROP 1 LASTPIN (-3150 5425) BN 4
J 2
(-3098 5433);
DISPLAY 0.489362 (-3098 5433);
PAINT MONO (-3098 5433);
FORCEPROP 2 LAST CDS_LIB standard
J 0
(-3100 5425);
DISPLAY INVISIBLE (-3100 5425);
FORCEPROP 2 LAST BOM_COST IO_SLOT
J 0
(-3600 5525);
DISPLAY 0.829787 (-3600 5525);
DISPLAY INVISIBLE (-3600 5525);
FORCEPROP 2 LAST ROOM RISER1
J 0
(-3600 5475);
DISPLAY 0.829787 (-3600 5475);
PAINT RED (-3600 5475);
DISPLAY INVISIBLE (-3600 5475);
FORCEPROP 1 LAST BODY_TYPE PLUMBING
J 2
(-3100 5375);
DISPLAY 0.702128 (-3100 5375);
PAINT GREEN (-3100 5375);
DISPLAY INVISIBLE (-3100 5375);
FORCEPROP 1 LAST HDL_TAP TRUE
J 2
(-3425 5300);
DISPLAY 0.702128 (-3425 5300);
PAINT GREEN (-3425 5300);
DISPLAY INVISIBLE (-3425 5300);
FORCEPROP 1 LAST PATH I227
J 2
(-3098 5425);
DISPLAY 0.872340 (-3098 5425);
PAINT GREEN (-3098 5425);
DISPLAY INVISIBLE (-3098 5425);
FORCEADD TAP..6
R 2
(-2950 5275);
FORCEPROP 3 LASTPIN (-3000 5275) SIG_NAME GMI_CPU0_G2_CPU1_G0_TX_DN<5>
J 0
(-2990 5285);
DISPLAY 0.659574 (-2990 5285);
PAINT MONO (-2990 5285);
DISPLAY INVISIBLE (-2990 5285);
FORCEPROP 1 LASTPIN (-3000 5275) BN 5
J 2
(-2948 5283);
DISPLAY 0.489362 (-2948 5283);
PAINT MONO (-2948 5283);
FORCEPROP 2 LAST CDS_LIB standard
J 0
(-2950 5275);
DISPLAY INVISIBLE (-2950 5275);
FORCEPROP 2 LAST BOM_COST IO_SLOT
J 0
(-3450 5375);
DISPLAY 0.829787 (-3450 5375);
DISPLAY INVISIBLE (-3450 5375);
FORCEPROP 2 LAST ROOM RISER1
J 0
(-3450 5325);
DISPLAY 0.829787 (-3450 5325);
PAINT RED (-3450 5325);
DISPLAY INVISIBLE (-3450 5325);
FORCEPROP 1 LAST BODY_TYPE PLUMBING
J 2
(-2950 5225);
DISPLAY 0.702128 (-2950 5225);
PAINT GREEN (-2950 5225);
DISPLAY INVISIBLE (-2950 5225);
FORCEPROP 1 LAST HDL_TAP TRUE
J 2
(-3275 5150);
DISPLAY 0.702128 (-3275 5150);
PAINT GREEN (-3275 5150);
DISPLAY INVISIBLE (-3275 5150);
FORCEPROP 1 LAST PATH I228
J 2
(-2948 5275);
DISPLAY 0.872340 (-2948 5275);
PAINT GREEN (-2948 5275);
DISPLAY INVISIBLE (-2948 5275);
FORCEADD TAP..6
R 2
(-2950 5375);
FORCEPROP 3 LASTPIN (-3000 5375) SIG_NAME GMI_CPU0_G2_CPU1_G0_TX_DN<4>
J 0
(-2990 5385);
DISPLAY 0.659574 (-2990 5385);
PAINT MONO (-2990 5385);
DISPLAY INVISIBLE (-2990 5385);
FORCEPROP 1 LASTPIN (-3000 5375) BN 4
J 2
(-2948 5383);
DISPLAY 0.489362 (-2948 5383);
PAINT MONO (-2948 5383);
FORCEPROP 2 LAST CDS_LIB standard
J 0
(-2950 5375);
DISPLAY INVISIBLE (-2950 5375);
FORCEPROP 2 LAST BOM_COST IO_SLOT
J 0
(-3450 5475);
DISPLAY 0.829787 (-3450 5475);
DISPLAY INVISIBLE (-3450 5475);
FORCEPROP 2 LAST ROOM RISER1
J 0
(-3450 5425);
DISPLAY 0.829787 (-3450 5425);
PAINT RED (-3450 5425);
DISPLAY INVISIBLE (-3450 5425);
FORCEPROP 1 LAST BODY_TYPE PLUMBING
J 2
(-2950 5325);
DISPLAY 0.702128 (-2950 5325);
PAINT GREEN (-2950 5325);
DISPLAY INVISIBLE (-2950 5325);
FORCEPROP 1 LAST HDL_TAP TRUE
J 2
(-3275 5250);
DISPLAY 0.702128 (-3275 5250);
PAINT GREEN (-3275 5250);
DISPLAY INVISIBLE (-3275 5250);
FORCEPROP 1 LAST PATH I229
J 2
(-2948 5375);
DISPLAY 0.872340 (-2948 5375);
PAINT GREEN (-2948 5375);
DISPLAY INVISIBLE (-2948 5375);
FORCEADD TAP..6
R 2
(-2950 5175);
FORCEPROP 3 LASTPIN (-3000 5175) SIG_NAME GMI_CPU0_G2_CPU1_G0_TX_DN<6>
J 0
(-2990 5185);
DISPLAY 0.659574 (-2990 5185);
PAINT MONO (-2990 5185);
DISPLAY INVISIBLE (-2990 5185);
FORCEPROP 1 LASTPIN (-3000 5175) BN 6
J 2
(-2948 5183);
DISPLAY 0.489362 (-2948 5183);
PAINT MONO (-2948 5183);
FORCEPROP 2 LAST CDS_LIB standard
J 0
(-2950 5175);
DISPLAY INVISIBLE (-2950 5175);
FORCEPROP 2 LAST BOM_COST IO_SLOT
J 0
(-3450 5275);
DISPLAY 0.829787 (-3450 5275);
DISPLAY INVISIBLE (-3450 5275);
FORCEPROP 2 LAST ROOM RISER1
J 0
(-3450 5225);
DISPLAY 0.829787 (-3450 5225);
PAINT RED (-3450 5225);
DISPLAY INVISIBLE (-3450 5225);
FORCEPROP 1 LAST BODY_TYPE PLUMBING
J 2
(-2950 5125);
DISPLAY 0.702128 (-2950 5125);
PAINT GREEN (-2950 5125);
DISPLAY INVISIBLE (-2950 5125);
FORCEPROP 1 LAST HDL_TAP TRUE
J 2
(-3275 5050);
DISPLAY 0.702128 (-3275 5050);
PAINT GREEN (-3275 5050);
DISPLAY INVISIBLE (-3275 5050);
FORCEPROP 1 LAST PATH I230
J 2
(-2948 5175);
DISPLAY 0.872340 (-2948 5175);
PAINT GREEN (-2948 5175);
DISPLAY INVISIBLE (-2948 5175);
FORCEADD TAP..6
R 2
(-3100 5125);
FORCEPROP 3 LASTPIN (-3150 5125) SIG_NAME GMI_CPU0_G2_CPU1_G0_TX_DP<7>
J 0
(-3140 5135);
DISPLAY 0.659574 (-3140 5135);
PAINT MONO (-3140 5135);
DISPLAY INVISIBLE (-3140 5135);
FORCEPROP 1 LASTPIN (-3150 5125) BN 7
J 2
(-3098 5133);
DISPLAY 0.489362 (-3098 5133);
PAINT MONO (-3098 5133);
FORCEPROP 2 LAST CDS_LIB standard
J 0
(-3100 5125);
DISPLAY INVISIBLE (-3100 5125);
FORCEPROP 2 LAST BOM_COST IO_SLOT
J 0
(-3600 5225);
DISPLAY 0.829787 (-3600 5225);
DISPLAY INVISIBLE (-3600 5225);
FORCEPROP 2 LAST ROOM RISER1
J 0
(-3600 5175);
DISPLAY 0.829787 (-3600 5175);
PAINT RED (-3600 5175);
DISPLAY INVISIBLE (-3600 5175);
FORCEPROP 1 LAST BODY_TYPE PLUMBING
J 2
(-3100 5075);
DISPLAY 0.702128 (-3100 5075);
PAINT GREEN (-3100 5075);
DISPLAY INVISIBLE (-3100 5075);
FORCEPROP 1 LAST HDL_TAP TRUE
J 2
(-3425 5000);
DISPLAY 0.702128 (-3425 5000);
PAINT GREEN (-3425 5000);
DISPLAY INVISIBLE (-3425 5000);
FORCEPROP 1 LAST PATH I231
J 2
(-3098 5125);
DISPLAY 0.872340 (-3098 5125);
PAINT GREEN (-3098 5125);
DISPLAY INVISIBLE (-3098 5125);
FORCEADD TAP..6
R 2
(-3100 5325);
FORCEPROP 3 LASTPIN (-3150 5325) SIG_NAME GMI_CPU0_G2_CPU1_G0_TX_DP<5>
J 0
(-3140 5335);
DISPLAY 0.659574 (-3140 5335);
PAINT MONO (-3140 5335);
DISPLAY INVISIBLE (-3140 5335);
FORCEPROP 1 LASTPIN (-3150 5325) BN 5
J 2
(-3098 5333);
DISPLAY 0.489362 (-3098 5333);
PAINT MONO (-3098 5333);
FORCEPROP 2 LAST CDS_LIB standard
J 0
(-3100 5325);
DISPLAY INVISIBLE (-3100 5325);
FORCEPROP 2 LAST BOM_COST IO_SLOT
J 0
(-3600 5425);
DISPLAY 0.829787 (-3600 5425);
DISPLAY INVISIBLE (-3600 5425);
FORCEPROP 2 LAST ROOM RISER1
J 0
(-3600 5375);
DISPLAY 0.829787 (-3600 5375);
PAINT RED (-3600 5375);
DISPLAY INVISIBLE (-3600 5375);
FORCEPROP 1 LAST BODY_TYPE PLUMBING
J 2
(-3100 5275);
DISPLAY 0.702128 (-3100 5275);
PAINT GREEN (-3100 5275);
DISPLAY INVISIBLE (-3100 5275);
FORCEPROP 1 LAST HDL_TAP TRUE
J 2
(-3425 5200);
DISPLAY 0.702128 (-3425 5200);
PAINT GREEN (-3425 5200);
DISPLAY INVISIBLE (-3425 5200);
FORCEPROP 1 LAST PATH I232
J 2
(-3098 5325);
DISPLAY 0.872340 (-3098 5325);
PAINT GREEN (-3098 5325);
DISPLAY INVISIBLE (-3098 5325);
FORCEADD TAP..6
R 2
(-3100 5225);
FORCEPROP 3 LASTPIN (-3150 5225) SIG_NAME GMI_CPU0_G2_CPU1_G0_TX_DP<6>
J 0
(-3140 5235);
DISPLAY 0.659574 (-3140 5235);
PAINT MONO (-3140 5235);
DISPLAY INVISIBLE (-3140 5235);
FORCEPROP 1 LASTPIN (-3150 5225) BN 6
J 2
(-3098 5233);
DISPLAY 0.489362 (-3098 5233);
PAINT MONO (-3098 5233);
FORCEPROP 2 LAST CDS_LIB standard
J 0
(-3100 5225);
DISPLAY INVISIBLE (-3100 5225);
FORCEPROP 2 LAST BOM_COST IO_SLOT
J 0
(-3600 5325);
DISPLAY 0.829787 (-3600 5325);
DISPLAY INVISIBLE (-3600 5325);
FORCEPROP 2 LAST ROOM RISER1
J 0
(-3600 5275);
DISPLAY 0.829787 (-3600 5275);
PAINT RED (-3600 5275);
DISPLAY INVISIBLE (-3600 5275);
FORCEPROP 1 LAST BODY_TYPE PLUMBING
J 2
(-3100 5175);
DISPLAY 0.702128 (-3100 5175);
PAINT GREEN (-3100 5175);
DISPLAY INVISIBLE (-3100 5175);
FORCEPROP 1 LAST HDL_TAP TRUE
J 2
(-3425 5100);
DISPLAY 0.702128 (-3425 5100);
PAINT GREEN (-3425 5100);
DISPLAY INVISIBLE (-3425 5100);
FORCEPROP 1 LAST PATH I233
J 2
(-3098 5225);
DISPLAY 0.872340 (-3098 5225);
PAINT GREEN (-3098 5225);
DISPLAY INVISIBLE (-3098 5225);
FORCEADD TAP..6
R 2
(-2950 5075);
FORCEPROP 3 LASTPIN (-3000 5075) SIG_NAME GMI_CPU0_G2_CPU1_G0_TX_DN<7>
J 0
(-2990 5085);
DISPLAY 0.659574 (-2990 5085);
PAINT MONO (-2990 5085);
DISPLAY INVISIBLE (-2990 5085);
FORCEPROP 1 LASTPIN (-3000 5075) BN 7
J 2
(-2948 5083);
DISPLAY 0.489362 (-2948 5083);
PAINT MONO (-2948 5083);
FORCEPROP 2 LAST CDS_LIB standard
J 0
(-2950 5075);
DISPLAY INVISIBLE (-2950 5075);
FORCEPROP 2 LAST BOM_COST IO_SLOT
J 0
(-3450 5175);
DISPLAY 0.829787 (-3450 5175);
DISPLAY INVISIBLE (-3450 5175);
FORCEPROP 2 LAST ROOM RISER1
J 0
(-3450 5125);
DISPLAY 0.829787 (-3450 5125);
PAINT RED (-3450 5125);
DISPLAY INVISIBLE (-3450 5125);
FORCEPROP 1 LAST BODY_TYPE PLUMBING
J 2
(-2950 5025);
DISPLAY 0.702128 (-2950 5025);
PAINT GREEN (-2950 5025);
DISPLAY INVISIBLE (-2950 5025);
FORCEPROP 1 LAST HDL_TAP TRUE
J 2
(-3275 4950);
DISPLAY 0.702128 (-3275 4950);
PAINT GREEN (-3275 4950);
DISPLAY INVISIBLE (-3275 4950);
FORCEPROP 1 LAST PATH I234
J 2
(-2948 5075);
DISPLAY 0.872340 (-2948 5075);
PAINT GREEN (-2948 5075);
DISPLAY INVISIBLE (-2948 5075);
FORCEADD TAP..6
R 2
(-2950 4875);
FORCEPROP 3 LASTPIN (-3000 4875) SIG_NAME GMI_CPU0_G2_CPU1_G0_TX_DN<9>
J 0
(-2990 4885);
DISPLAY 0.659574 (-2990 4885);
PAINT MONO (-2990 4885);
DISPLAY INVISIBLE (-2990 4885);
FORCEPROP 1 LASTPIN (-3000 4875) BN 9
J 2
(-2948 4883);
DISPLAY 0.489362 (-2948 4883);
PAINT MONO (-2948 4883);
FORCEPROP 2 LAST CDS_LIB standard
J 0
(-2950 4875);
DISPLAY INVISIBLE (-2950 4875);
FORCEPROP 2 LAST BOM_COST IO_SLOT
J 0
(-3450 4975);
DISPLAY 0.829787 (-3450 4975);
DISPLAY INVISIBLE (-3450 4975);
FORCEPROP 2 LAST ROOM RISER1
J 0
(-3450 4925);
DISPLAY 0.829787 (-3450 4925);
PAINT RED (-3450 4925);
DISPLAY INVISIBLE (-3450 4925);
FORCEPROP 1 LAST BODY_TYPE PLUMBING
J 2
(-2950 4825);
DISPLAY 0.702128 (-2950 4825);
PAINT GREEN (-2950 4825);
DISPLAY INVISIBLE (-2950 4825);
FORCEPROP 1 LAST HDL_TAP TRUE
J 2
(-3275 4750);
DISPLAY 0.702128 (-3275 4750);
PAINT GREEN (-3275 4750);
DISPLAY INVISIBLE (-3275 4750);
FORCEPROP 1 LAST PATH I235
J 2
(-2948 4875);
DISPLAY 0.872340 (-2948 4875);
PAINT GREEN (-2948 4875);
DISPLAY INVISIBLE (-2948 4875);
FORCEADD TAP..6
R 2
(-2950 4975);
FORCEPROP 3 LASTPIN (-3000 4975) SIG_NAME GMI_CPU0_G2_CPU1_G0_TX_DN<8>
J 0
(-2990 4985);
DISPLAY 0.659574 (-2990 4985);
PAINT MONO (-2990 4985);
DISPLAY INVISIBLE (-2990 4985);
FORCEPROP 1 LASTPIN (-3000 4975) BN 8
J 2
(-2948 4983);
DISPLAY 0.489362 (-2948 4983);
PAINT MONO (-2948 4983);
FORCEPROP 2 LAST CDS_LIB standard
J 0
(-2950 4975);
DISPLAY INVISIBLE (-2950 4975);
FORCEPROP 2 LAST BOM_COST IO_SLOT
J 0
(-3450 5075);
DISPLAY 0.829787 (-3450 5075);
DISPLAY INVISIBLE (-3450 5075);
FORCEPROP 2 LAST ROOM RISER1
J 0
(-3450 5025);
DISPLAY 0.829787 (-3450 5025);
PAINT RED (-3450 5025);
DISPLAY INVISIBLE (-3450 5025);
FORCEPROP 1 LAST BODY_TYPE PLUMBING
J 2
(-2950 4925);
DISPLAY 0.702128 (-2950 4925);
PAINT GREEN (-2950 4925);
DISPLAY INVISIBLE (-2950 4925);
FORCEPROP 1 LAST HDL_TAP TRUE
J 2
(-3275 4850);
DISPLAY 0.702128 (-3275 4850);
PAINT GREEN (-3275 4850);
DISPLAY INVISIBLE (-3275 4850);
FORCEPROP 1 LAST PATH I236
J 2
(-2948 4975);
DISPLAY 0.872340 (-2948 4975);
PAINT GREEN (-2948 4975);
DISPLAY INVISIBLE (-2948 4975);
FORCEADD TAP..6
R 2
(-3100 5025);
FORCEPROP 3 LASTPIN (-3150 5025) SIG_NAME GMI_CPU0_G2_CPU1_G0_TX_DP<8>
J 0
(-3140 5035);
DISPLAY 0.659574 (-3140 5035);
PAINT MONO (-3140 5035);
DISPLAY INVISIBLE (-3140 5035);
FORCEPROP 1 LASTPIN (-3150 5025) BN 8
J 2
(-3098 5033);
DISPLAY 0.489362 (-3098 5033);
PAINT MONO (-3098 5033);
FORCEPROP 2 LAST CDS_LIB standard
J 0
(-3100 5025);
DISPLAY INVISIBLE (-3100 5025);
FORCEPROP 2 LAST BOM_COST IO_SLOT
J 0
(-3600 5125);
DISPLAY 0.829787 (-3600 5125);
DISPLAY INVISIBLE (-3600 5125);
FORCEPROP 2 LAST ROOM RISER1
J 0
(-3600 5075);
DISPLAY 0.829787 (-3600 5075);
PAINT RED (-3600 5075);
DISPLAY INVISIBLE (-3600 5075);
FORCEPROP 1 LAST BODY_TYPE PLUMBING
J 2
(-3100 4975);
DISPLAY 0.702128 (-3100 4975);
PAINT GREEN (-3100 4975);
DISPLAY INVISIBLE (-3100 4975);
FORCEPROP 1 LAST HDL_TAP TRUE
J 2
(-3425 4900);
DISPLAY 0.702128 (-3425 4900);
PAINT GREEN (-3425 4900);
DISPLAY INVISIBLE (-3425 4900);
FORCEPROP 1 LAST PATH I237
J 2
(-3098 5025);
DISPLAY 0.872340 (-3098 5025);
PAINT GREEN (-3098 5025);
DISPLAY INVISIBLE (-3098 5025);
FORCEADD TAP..6
R 2
(-3100 4925);
FORCEPROP 3 LASTPIN (-3150 4925) SIG_NAME GMI_CPU0_G2_CPU1_G0_TX_DP<9>
J 0
(-3140 4935);
DISPLAY 0.659574 (-3140 4935);
PAINT MONO (-3140 4935);
DISPLAY INVISIBLE (-3140 4935);
FORCEPROP 1 LASTPIN (-3150 4925) BN 9
J 2
(-3098 4933);
DISPLAY 0.489362 (-3098 4933);
PAINT MONO (-3098 4933);
FORCEPROP 2 LAST CDS_LIB standard
J 0
(-3100 4925);
DISPLAY INVISIBLE (-3100 4925);
FORCEPROP 2 LAST BOM_COST IO_SLOT
J 0
(-3600 5025);
DISPLAY 0.829787 (-3600 5025);
DISPLAY INVISIBLE (-3600 5025);
FORCEPROP 2 LAST ROOM RISER1
J 0
(-3600 4975);
DISPLAY 0.829787 (-3600 4975);
PAINT RED (-3600 4975);
DISPLAY INVISIBLE (-3600 4975);
FORCEPROP 1 LAST BODY_TYPE PLUMBING
J 2
(-3100 4875);
DISPLAY 0.702128 (-3100 4875);
PAINT GREEN (-3100 4875);
DISPLAY INVISIBLE (-3100 4875);
FORCEPROP 1 LAST HDL_TAP TRUE
J 2
(-3425 4800);
DISPLAY 0.702128 (-3425 4800);
PAINT GREEN (-3425 4800);
DISPLAY INVISIBLE (-3425 4800);
FORCEPROP 1 LAST PATH I238
J 2
(-3098 4925);
DISPLAY 0.872340 (-3098 4925);
PAINT GREEN (-3098 4925);
DISPLAY INVISIBLE (-3098 4925);
FORCEADD TAP..6
R 2
(-2950 4775);
FORCEPROP 3 LASTPIN (-3000 4775) SIG_NAME GMI_CPU0_G2_CPU1_G0_TX_DN<10>
J 0
(-2990 4785);
DISPLAY 0.659574 (-2990 4785);
PAINT MONO (-2990 4785);
DISPLAY INVISIBLE (-2990 4785);
FORCEPROP 1 LASTPIN (-3000 4775) BN 10
J 2
(-2948 4783);
DISPLAY 0.489362 (-2948 4783);
PAINT MONO (-2948 4783);
FORCEPROP 2 LAST CDS_LIB standard
J 0
(-2950 4775);
DISPLAY INVISIBLE (-2950 4775);
FORCEPROP 2 LAST BOM_COST IO_SLOT
J 0
(-3450 4875);
DISPLAY 0.829787 (-3450 4875);
DISPLAY INVISIBLE (-3450 4875);
FORCEPROP 2 LAST ROOM RISER1
J 0
(-3450 4825);
DISPLAY 0.829787 (-3450 4825);
PAINT RED (-3450 4825);
DISPLAY INVISIBLE (-3450 4825);
FORCEPROP 1 LAST BODY_TYPE PLUMBING
J 2
(-2950 4725);
DISPLAY 0.702128 (-2950 4725);
PAINT GREEN (-2950 4725);
DISPLAY INVISIBLE (-2950 4725);
FORCEPROP 1 LAST HDL_TAP TRUE
J 2
(-3275 4650);
DISPLAY 0.702128 (-3275 4650);
PAINT GREEN (-3275 4650);
DISPLAY INVISIBLE (-3275 4650);
FORCEPROP 1 LAST PATH I239
J 2
(-2948 4775);
DISPLAY 0.872340 (-2948 4775);
PAINT GREEN (-2948 4775);
DISPLAY INVISIBLE (-2948 4775);
FORCEADD TAP..6
R 2
(-2950 4675);
FORCEPROP 3 LASTPIN (-3000 4675) SIG_NAME GMI_CPU0_G2_CPU1_G0_TX_DN<11>
J 0
(-2990 4685);
DISPLAY 0.659574 (-2990 4685);
PAINT MONO (-2990 4685);
DISPLAY INVISIBLE (-2990 4685);
FORCEPROP 1 LASTPIN (-3000 4675) BN 11
J 2
(-2948 4683);
DISPLAY 0.489362 (-2948 4683);
PAINT MONO (-2948 4683);
FORCEPROP 2 LAST CDS_LIB standard
J 0
(-2950 4675);
DISPLAY INVISIBLE (-2950 4675);
FORCEPROP 2 LAST BOM_COST IO_SLOT
J 0
(-3450 4775);
DISPLAY 0.829787 (-3450 4775);
DISPLAY INVISIBLE (-3450 4775);
FORCEPROP 2 LAST ROOM RISER1
J 0
(-3450 4725);
DISPLAY 0.829787 (-3450 4725);
PAINT RED (-3450 4725);
DISPLAY INVISIBLE (-3450 4725);
FORCEPROP 1 LAST BODY_TYPE PLUMBING
J 2
(-2950 4625);
DISPLAY 0.702128 (-2950 4625);
PAINT GREEN (-2950 4625);
DISPLAY INVISIBLE (-2950 4625);
FORCEPROP 1 LAST HDL_TAP TRUE
J 2
(-3275 4550);
DISPLAY 0.702128 (-3275 4550);
PAINT GREEN (-3275 4550);
DISPLAY INVISIBLE (-3275 4550);
FORCEPROP 1 LAST PATH I240
J 2
(-2948 4675);
DISPLAY 0.872340 (-2948 4675);
PAINT GREEN (-2948 4675);
DISPLAY INVISIBLE (-2948 4675);
FORCEADD TAP..6
R 2
(-3100 4625);
FORCEPROP 3 LASTPIN (-3150 4625) SIG_NAME GMI_CPU0_G2_CPU1_G0_TX_DP<12>
J 0
(-3140 4635);
DISPLAY 0.659574 (-3140 4635);
PAINT MONO (-3140 4635);
DISPLAY INVISIBLE (-3140 4635);
FORCEPROP 1 LASTPIN (-3150 4625) BN 12
J 2
(-3098 4633);
DISPLAY 0.489362 (-3098 4633);
PAINT MONO (-3098 4633);
FORCEPROP 2 LAST CDS_LIB standard
J 0
(-3100 4625);
DISPLAY INVISIBLE (-3100 4625);
FORCEPROP 2 LAST BOM_COST IO_SLOT
J 0
(-3600 4725);
DISPLAY 0.829787 (-3600 4725);
DISPLAY INVISIBLE (-3600 4725);
FORCEPROP 2 LAST ROOM RISER1
J 0
(-3600 4675);
DISPLAY 0.829787 (-3600 4675);
PAINT RED (-3600 4675);
DISPLAY INVISIBLE (-3600 4675);
FORCEPROP 1 LAST BODY_TYPE PLUMBING
J 2
(-3100 4575);
DISPLAY 0.702128 (-3100 4575);
PAINT GREEN (-3100 4575);
DISPLAY INVISIBLE (-3100 4575);
FORCEPROP 1 LAST HDL_TAP TRUE
J 2
(-3425 4500);
DISPLAY 0.702128 (-3425 4500);
PAINT GREEN (-3425 4500);
DISPLAY INVISIBLE (-3425 4500);
FORCEPROP 1 LAST PATH I241
J 2
(-3098 4625);
DISPLAY 0.872340 (-3098 4625);
PAINT GREEN (-3098 4625);
DISPLAY INVISIBLE (-3098 4625);
FORCEADD TAP..6
R 2
(-3100 4825);
FORCEPROP 3 LASTPIN (-3150 4825) SIG_NAME GMI_CPU0_G2_CPU1_G0_TX_DP<10>
J 0
(-3140 4835);
DISPLAY 0.659574 (-3140 4835);
PAINT MONO (-3140 4835);
DISPLAY INVISIBLE (-3140 4835);
FORCEPROP 1 LASTPIN (-3150 4825) BN 10
J 2
(-3098 4833);
DISPLAY 0.489362 (-3098 4833);
PAINT MONO (-3098 4833);
FORCEPROP 2 LAST CDS_LIB standard
J 0
(-3100 4825);
DISPLAY INVISIBLE (-3100 4825);
FORCEPROP 2 LAST BOM_COST IO_SLOT
J 0
(-3600 4925);
DISPLAY 0.829787 (-3600 4925);
DISPLAY INVISIBLE (-3600 4925);
FORCEPROP 2 LAST ROOM RISER1
J 0
(-3600 4875);
DISPLAY 0.829787 (-3600 4875);
PAINT RED (-3600 4875);
DISPLAY INVISIBLE (-3600 4875);
FORCEPROP 1 LAST BODY_TYPE PLUMBING
J 2
(-3100 4775);
DISPLAY 0.702128 (-3100 4775);
PAINT GREEN (-3100 4775);
DISPLAY INVISIBLE (-3100 4775);
FORCEPROP 1 LAST HDL_TAP TRUE
J 2
(-3425 4700);
DISPLAY 0.702128 (-3425 4700);
PAINT GREEN (-3425 4700);
DISPLAY INVISIBLE (-3425 4700);
FORCEPROP 1 LAST PATH I242
J 2
(-3098 4825);
DISPLAY 0.872340 (-3098 4825);
PAINT GREEN (-3098 4825);
DISPLAY INVISIBLE (-3098 4825);
FORCEADD TAP..6
R 2
(-3100 4725);
FORCEPROP 3 LASTPIN (-3150 4725) SIG_NAME GMI_CPU0_G2_CPU1_G0_TX_DP<11>
J 0
(-3140 4735);
DISPLAY 0.659574 (-3140 4735);
PAINT MONO (-3140 4735);
DISPLAY INVISIBLE (-3140 4735);
FORCEPROP 1 LASTPIN (-3150 4725) BN 11
J 2
(-3098 4733);
DISPLAY 0.489362 (-3098 4733);
PAINT MONO (-3098 4733);
FORCEPROP 2 LAST CDS_LIB standard
J 0
(-3100 4725);
DISPLAY INVISIBLE (-3100 4725);
FORCEPROP 2 LAST BOM_COST IO_SLOT
J 0
(-3600 4825);
DISPLAY 0.829787 (-3600 4825);
DISPLAY INVISIBLE (-3600 4825);
FORCEPROP 2 LAST ROOM RISER1
J 0
(-3600 4775);
DISPLAY 0.829787 (-3600 4775);
PAINT RED (-3600 4775);
DISPLAY INVISIBLE (-3600 4775);
FORCEPROP 1 LAST BODY_TYPE PLUMBING
J 2
(-3100 4675);
DISPLAY 0.702128 (-3100 4675);
PAINT GREEN (-3100 4675);
DISPLAY INVISIBLE (-3100 4675);
FORCEPROP 1 LAST HDL_TAP TRUE
J 2
(-3425 4600);
DISPLAY 0.702128 (-3425 4600);
PAINT GREEN (-3425 4600);
DISPLAY INVISIBLE (-3425 4600);
FORCEPROP 1 LAST PATH I243
J 2
(-3098 4725);
DISPLAY 0.872340 (-3098 4725);
PAINT GREEN (-3098 4725);
DISPLAY INVISIBLE (-3098 4725);
FORCEADD TAP..6
R 2
(-2950 4575);
FORCEPROP 3 LASTPIN (-3000 4575) SIG_NAME GMI_CPU0_G2_CPU1_G0_TX_DN<12>
J 0
(-2990 4585);
DISPLAY 0.659574 (-2990 4585);
PAINT MONO (-2990 4585);
DISPLAY INVISIBLE (-2990 4585);
FORCEPROP 1 LASTPIN (-3000 4575) BN 12
J 2
(-2948 4583);
DISPLAY 0.489362 (-2948 4583);
PAINT MONO (-2948 4583);
FORCEPROP 2 LAST CDS_LIB standard
J 0
(-2950 4575);
DISPLAY INVISIBLE (-2950 4575);
FORCEPROP 2 LAST BOM_COST IO_SLOT
J 0
(-3450 4675);
DISPLAY 0.829787 (-3450 4675);
DISPLAY INVISIBLE (-3450 4675);
FORCEPROP 2 LAST ROOM RISER1
J 0
(-3450 4625);
DISPLAY 0.829787 (-3450 4625);
PAINT RED (-3450 4625);
DISPLAY INVISIBLE (-3450 4625);
FORCEPROP 1 LAST BODY_TYPE PLUMBING
J 2
(-2950 4525);
DISPLAY 0.702128 (-2950 4525);
PAINT GREEN (-2950 4525);
DISPLAY INVISIBLE (-2950 4525);
FORCEPROP 1 LAST HDL_TAP TRUE
J 2
(-3275 4450);
DISPLAY 0.702128 (-3275 4450);
PAINT GREEN (-3275 4450);
DISPLAY INVISIBLE (-3275 4450);
FORCEPROP 1 LAST PATH I244
J 2
(-2948 4575);
DISPLAY 0.872340 (-2948 4575);
PAINT GREEN (-2948 4575);
DISPLAY INVISIBLE (-2948 4575);
FORCEADD TAP..6
R 2
(-2950 4375);
FORCEPROP 3 LASTPIN (-3000 4375) SIG_NAME GMI_CPU0_G2_CPU1_G0_TX_DN<14>
J 0
(-2990 4385);
DISPLAY 0.659574 (-2990 4385);
PAINT MONO (-2990 4385);
DISPLAY INVISIBLE (-2990 4385);
FORCEPROP 1 LASTPIN (-3000 4375) BN 14
J 2
(-2948 4383);
DISPLAY 0.489362 (-2948 4383);
PAINT MONO (-2948 4383);
FORCEPROP 2 LAST BOM_COST IO_SLOT
J 0
(-3450 4475);
DISPLAY 0.829787 (-3450 4475);
DISPLAY INVISIBLE (-3450 4475);
FORCEPROP 2 LAST CDS_LIB standard
J 0
(-2950 4375);
DISPLAY INVISIBLE (-2950 4375);
FORCEPROP 2 LAST ROOM RISER1
J 0
(-3450 4425);
DISPLAY 0.829787 (-3450 4425);
PAINT RED (-3450 4425);
DISPLAY INVISIBLE (-3450 4425);
FORCEPROP 1 LAST BODY_TYPE PLUMBING
J 2
(-2950 4325);
DISPLAY 0.702128 (-2950 4325);
PAINT GREEN (-2950 4325);
DISPLAY INVISIBLE (-2950 4325);
FORCEPROP 1 LAST HDL_TAP TRUE
J 2
(-3275 4250);
DISPLAY 0.702128 (-3275 4250);
PAINT GREEN (-3275 4250);
DISPLAY INVISIBLE (-3275 4250);
FORCEPROP 1 LAST PATH I245
J 2
(-2948 4375);
DISPLAY 0.872340 (-2948 4375);
PAINT GREEN (-2948 4375);
DISPLAY INVISIBLE (-2948 4375);
FORCEADD TAP..6
R 2
(-2950 4475);
FORCEPROP 3 LASTPIN (-3000 4475) SIG_NAME GMI_CPU0_G2_CPU1_G0_TX_DN<13>
J 0
(-2990 4485);
DISPLAY 0.659574 (-2990 4485);
PAINT MONO (-2990 4485);
DISPLAY INVISIBLE (-2990 4485);
FORCEPROP 1 LASTPIN (-3000 4475) BN 13
J 2
(-2948 4483);
DISPLAY 0.489362 (-2948 4483);
PAINT MONO (-2948 4483);
FORCEPROP 2 LAST CDS_LIB standard
J 0
(-2950 4475);
DISPLAY INVISIBLE (-2950 4475);
FORCEPROP 2 LAST BOM_COST IO_SLOT
J 0
(-3450 4575);
DISPLAY 0.829787 (-3450 4575);
DISPLAY INVISIBLE (-3450 4575);
FORCEPROP 2 LAST ROOM RISER1
J 0
(-3450 4525);
DISPLAY 0.829787 (-3450 4525);
PAINT RED (-3450 4525);
DISPLAY INVISIBLE (-3450 4525);
FORCEPROP 1 LAST BODY_TYPE PLUMBING
J 2
(-2950 4425);
DISPLAY 0.702128 (-2950 4425);
PAINT GREEN (-2950 4425);
DISPLAY INVISIBLE (-2950 4425);
FORCEPROP 1 LAST HDL_TAP TRUE
J 2
(-3275 4350);
DISPLAY 0.702128 (-3275 4350);
PAINT GREEN (-3275 4350);
DISPLAY INVISIBLE (-3275 4350);
FORCEPROP 1 LAST PATH I246
J 2
(-2948 4475);
DISPLAY 0.872340 (-2948 4475);
PAINT GREEN (-2948 4475);
DISPLAY INVISIBLE (-2948 4475);
FORCEADD TAP..6
R 2
(-3100 4425);
FORCEPROP 3 LASTPIN (-3150 4425) SIG_NAME GMI_CPU0_G2_CPU1_G0_TX_DP<14>
J 0
(-3140 4435);
DISPLAY 0.659574 (-3140 4435);
PAINT MONO (-3140 4435);
DISPLAY INVISIBLE (-3140 4435);
FORCEPROP 1 LASTPIN (-3150 4425) BN 14
J 2
(-3098 4433);
DISPLAY 0.489362 (-3098 4433);
PAINT MONO (-3098 4433);
FORCEPROP 2 LAST CDS_LIB standard
J 0
(-3100 4425);
DISPLAY INVISIBLE (-3100 4425);
FORCEPROP 2 LAST BOM_COST IO_SLOT
J 0
(-3600 4525);
DISPLAY 0.829787 (-3600 4525);
DISPLAY INVISIBLE (-3600 4525);
FORCEPROP 2 LAST ROOM RISER1
J 0
(-3600 4475);
DISPLAY 0.829787 (-3600 4475);
PAINT RED (-3600 4475);
DISPLAY INVISIBLE (-3600 4475);
FORCEPROP 1 LAST BODY_TYPE PLUMBING
J 2
(-3100 4375);
DISPLAY 0.702128 (-3100 4375);
PAINT GREEN (-3100 4375);
DISPLAY INVISIBLE (-3100 4375);
FORCEPROP 1 LAST HDL_TAP TRUE
J 2
(-3425 4300);
DISPLAY 0.702128 (-3425 4300);
PAINT GREEN (-3425 4300);
DISPLAY INVISIBLE (-3425 4300);
FORCEPROP 1 LAST PATH I247
J 2
(-3098 4425);
DISPLAY 0.872340 (-3098 4425);
PAINT GREEN (-3098 4425);
DISPLAY INVISIBLE (-3098 4425);
FORCEADD TAP..6
R 2
(-3100 4525);
FORCEPROP 3 LASTPIN (-3150 4525) SIG_NAME GMI_CPU0_G2_CPU1_G0_TX_DP<13>
J 0
(-3140 4535);
DISPLAY 0.659574 (-3140 4535);
PAINT MONO (-3140 4535);
DISPLAY INVISIBLE (-3140 4535);
FORCEPROP 1 LASTPIN (-3150 4525) BN 13
J 2
(-3098 4533);
DISPLAY 0.489362 (-3098 4533);
PAINT MONO (-3098 4533);
FORCEPROP 2 LAST CDS_LIB standard
J 0
(-3100 4525);
DISPLAY INVISIBLE (-3100 4525);
FORCEPROP 2 LAST BOM_COST IO_SLOT
J 0
(-3600 4625);
DISPLAY 0.829787 (-3600 4625);
DISPLAY INVISIBLE (-3600 4625);
FORCEPROP 2 LAST ROOM RISER1
J 0
(-3600 4575);
DISPLAY 0.829787 (-3600 4575);
PAINT RED (-3600 4575);
DISPLAY INVISIBLE (-3600 4575);
FORCEPROP 1 LAST BODY_TYPE PLUMBING
J 2
(-3100 4475);
DISPLAY 0.702128 (-3100 4475);
PAINT GREEN (-3100 4475);
DISPLAY INVISIBLE (-3100 4475);
FORCEPROP 1 LAST HDL_TAP TRUE
J 2
(-3425 4400);
DISPLAY 0.702128 (-3425 4400);
PAINT GREEN (-3425 4400);
DISPLAY INVISIBLE (-3425 4400);
FORCEPROP 1 LAST PATH I248
J 2
(-3098 4525);
DISPLAY 0.872340 (-3098 4525);
PAINT GREEN (-3098 4525);
DISPLAY INVISIBLE (-3098 4525);
FORCEADD TAP..6
R 2
(-2950 4275);
FORCEPROP 3 LASTPIN (-3000 4275) SIG_NAME GMI_CPU0_G2_CPU1_G0_TX_DN<15>
J 0
(-2990 4285);
DISPLAY 0.659574 (-2990 4285);
PAINT MONO (-2990 4285);
DISPLAY INVISIBLE (-2990 4285);
FORCEPROP 1 LASTPIN (-3000 4275) BN 15
J 2
(-2948 4283);
DISPLAY 0.489362 (-2948 4283);
PAINT MONO (-2948 4283);
FORCEPROP 2 LAST CDS_LIB standard
J 0
(-2950 4275);
DISPLAY INVISIBLE (-2950 4275);
FORCEPROP 2 LAST BOM_COST IO_SLOT
J 0
(-3450 4375);
DISPLAY 0.829787 (-3450 4375);
DISPLAY INVISIBLE (-3450 4375);
FORCEPROP 2 LAST ROOM RISER1
J 0
(-3450 4325);
DISPLAY 0.829787 (-3450 4325);
PAINT RED (-3450 4325);
DISPLAY INVISIBLE (-3450 4325);
FORCEPROP 1 LAST BODY_TYPE PLUMBING
J 2
(-2950 4225);
DISPLAY 0.702128 (-2950 4225);
PAINT GREEN (-2950 4225);
DISPLAY INVISIBLE (-2950 4225);
FORCEPROP 1 LAST HDL_TAP TRUE
J 2
(-3275 4150);
DISPLAY 0.702128 (-3275 4150);
PAINT GREEN (-3275 4150);
DISPLAY INVISIBLE (-3275 4150);
FORCEPROP 1 LAST PATH I249
J 2
(-2948 4275);
DISPLAY 0.872340 (-2948 4275);
PAINT GREEN (-2948 4275);
DISPLAY INVISIBLE (-2948 4275);
FORCEADD TAP..6
R 2
(-3100 4325);
FORCEPROP 3 LASTPIN (-3150 4325) SIG_NAME GMI_CPU0_G2_CPU1_G0_TX_DP<15>
J 0
(-3140 4335);
DISPLAY 0.659574 (-3140 4335);
PAINT MONO (-3140 4335);
DISPLAY INVISIBLE (-3140 4335);
FORCEPROP 1 LASTPIN (-3150 4325) BN 15
J 2
(-3098 4333);
DISPLAY 0.489362 (-3098 4333);
PAINT MONO (-3098 4333);
FORCEPROP 2 LAST CDS_LIB standard
J 0
(-3100 4325);
DISPLAY INVISIBLE (-3100 4325);
FORCEPROP 2 LAST BOM_COST IO_SLOT
J 0
(-3600 4425);
DISPLAY 0.829787 (-3600 4425);
DISPLAY INVISIBLE (-3600 4425);
FORCEPROP 2 LAST ROOM RISER1
J 0
(-3600 4375);
DISPLAY 0.829787 (-3600 4375);
PAINT RED (-3600 4375);
DISPLAY INVISIBLE (-3600 4375);
FORCEPROP 1 LAST BODY_TYPE PLUMBING
J 2
(-3100 4275);
DISPLAY 0.702128 (-3100 4275);
PAINT GREEN (-3100 4275);
DISPLAY INVISIBLE (-3100 4275);
FORCEPROP 1 LAST HDL_TAP TRUE
J 2
(-3425 4200);
DISPLAY 0.702128 (-3425 4200);
PAINT GREEN (-3425 4200);
DISPLAY INVISIBLE (-3425 4200);
FORCEPROP 1 LAST PATH I250
J 2
(-3098 4325);
DISPLAY 0.872340 (-3098 4325);
PAINT GREEN (-3098 4325);
DISPLAY INVISIBLE (-3098 4325);
FORCEADD TAP..6
(-6525 5825);
FORCEPROP 3 LASTPIN (-6475 5825) SIG_NAME GMI_CPU1_G0_CPU0_G2_TX_DP<0>
J 0
(-6465 5835);
DISPLAY 0.659574 (-6465 5835);
PAINT MONO (-6465 5835);
DISPLAY INVISIBLE (-6465 5835);
FORCEPROP 1 LASTPIN (-6475 5825) BN 0
J 0
(-6527 5833);
DISPLAY 0.489362 (-6527 5833);
PAINT MONO (-6527 5833);
FORCEPROP 2 LAST CDS_LIB mstr_standard
J 0
(-6525 5825);
DISPLAY INVISIBLE (-6525 5825);
FORCEPROP 1 LAST BODY_TYPE PLUMBING
J 0
(-6525 5775);
DISPLAY 0.574468 (-6525 5775);
PAINT GREEN (-6525 5775);
DISPLAY INVISIBLE (-6525 5775);
FORCEPROP 1 LAST HDL_TAP TRUE
J 0
(-6200 5700);
DISPLAY 0.574468 (-6200 5700);
PAINT GREEN (-6200 5700);
DISPLAY INVISIBLE (-6200 5700);
FORCEPROP 1 LAST PATH I251
J 0
(-6527 5825);
DISPLAY 0.872340 (-6527 5825);
PAINT GREEN (-6527 5825);
DISPLAY INVISIBLE (-6527 5825);
FORCEADD TAP..6
(-6525 5725);
FORCEPROP 3 LASTPIN (-6475 5725) SIG_NAME GMI_CPU1_G0_CPU0_G2_TX_DP<1>
J 0
(-6465 5735);
DISPLAY 0.659574 (-6465 5735);
PAINT MONO (-6465 5735);
DISPLAY INVISIBLE (-6465 5735);
FORCEPROP 1 LASTPIN (-6475 5725) BN 1
J 0
(-6527 5733);
DISPLAY 0.489362 (-6527 5733);
PAINT MONO (-6527 5733);
FORCEPROP 2 LAST CDS_LIB mstr_standard
J 0
(-6525 5725);
DISPLAY INVISIBLE (-6525 5725);
FORCEPROP 1 LAST BODY_TYPE PLUMBING
J 0
(-6525 5675);
DISPLAY 0.574468 (-6525 5675);
PAINT GREEN (-6525 5675);
DISPLAY INVISIBLE (-6525 5675);
FORCEPROP 1 LAST HDL_TAP TRUE
J 0
(-6200 5600);
DISPLAY 0.574468 (-6200 5600);
PAINT GREEN (-6200 5600);
DISPLAY INVISIBLE (-6200 5600);
FORCEPROP 1 LAST PATH I252
J 0
(-6527 5725);
DISPLAY 0.872340 (-6527 5725);
PAINT GREEN (-6527 5725);
DISPLAY INVISIBLE (-6527 5725);
FORCEADD TAP..6
(-6675 5775);
FORCEPROP 3 LASTPIN (-6625 5775) SIG_NAME GMI_CPU1_G0_CPU0_G2_TX_DN<0>
J 0
(-6615 5785);
DISPLAY 0.659574 (-6615 5785);
PAINT MONO (-6615 5785);
DISPLAY INVISIBLE (-6615 5785);
FORCEPROP 1 LASTPIN (-6625 5775) BN 0
J 0
(-6677 5783);
DISPLAY 0.489362 (-6677 5783);
PAINT MONO (-6677 5783);
FORCEPROP 2 LAST CDS_LIB mstr_standard
J 0
(-6675 5775);
DISPLAY INVISIBLE (-6675 5775);
FORCEPROP 1 LAST BODY_TYPE PLUMBING
J 0
(-6675 5725);
DISPLAY 0.574468 (-6675 5725);
PAINT GREEN (-6675 5725);
DISPLAY INVISIBLE (-6675 5725);
FORCEPROP 1 LAST HDL_TAP TRUE
J 0
(-6350 5650);
DISPLAY 0.574468 (-6350 5650);
PAINT GREEN (-6350 5650);
DISPLAY INVISIBLE (-6350 5650);
FORCEPROP 1 LAST PATH I253
J 0
(-6677 5775);
DISPLAY 0.872340 (-6677 5775);
PAINT GREEN (-6677 5775);
DISPLAY INVISIBLE (-6677 5775);
FORCEADD TAP..6
(-6675 5675);
FORCEPROP 3 LASTPIN (-6625 5675) SIG_NAME GMI_CPU1_G0_CPU0_G2_TX_DN<1>
J 0
(-6615 5685);
DISPLAY 0.659574 (-6615 5685);
PAINT MONO (-6615 5685);
DISPLAY INVISIBLE (-6615 5685);
FORCEPROP 1 LASTPIN (-6625 5675) BN 1
J 0
(-6677 5683);
DISPLAY 0.489362 (-6677 5683);
PAINT MONO (-6677 5683);
FORCEPROP 2 LAST CDS_LIB mstr_standard
J 0
(-6675 5675);
DISPLAY INVISIBLE (-6675 5675);
FORCEPROP 1 LAST BODY_TYPE PLUMBING
J 0
(-6675 5625);
DISPLAY 0.574468 (-6675 5625);
PAINT GREEN (-6675 5625);
DISPLAY INVISIBLE (-6675 5625);
FORCEPROP 1 LAST HDL_TAP TRUE
J 0
(-6350 5550);
DISPLAY 0.574468 (-6350 5550);
PAINT GREEN (-6350 5550);
DISPLAY INVISIBLE (-6350 5550);
FORCEPROP 1 LAST PATH I254
J 0
(-6677 5675);
DISPLAY 0.872340 (-6677 5675);
PAINT GREEN (-6677 5675);
DISPLAY INVISIBLE (-6677 5675);
FORCEADD TAP..6
(-6525 5525);
FORCEPROP 3 LASTPIN (-6475 5525) SIG_NAME GMI_CPU1_G0_CPU0_G2_TX_DP<3>
J 0
(-6465 5535);
DISPLAY 0.659574 (-6465 5535);
PAINT MONO (-6465 5535);
DISPLAY INVISIBLE (-6465 5535);
FORCEPROP 1 LASTPIN (-6475 5525) BN 3
J 0
(-6527 5533);
DISPLAY 0.489362 (-6527 5533);
PAINT MONO (-6527 5533);
FORCEPROP 2 LAST CDS_LIB standard
J 0
(-6525 5525);
DISPLAY INVISIBLE (-6525 5525);
FORCEPROP 1 LAST BODY_TYPE PLUMBING
J 0
(-6525 5475);
DISPLAY 0.574468 (-6525 5475);
PAINT GREEN (-6525 5475);
DISPLAY INVISIBLE (-6525 5475);
FORCEPROP 1 LAST HDL_TAP TRUE
J 0
(-6200 5400);
DISPLAY 0.574468 (-6200 5400);
PAINT GREEN (-6200 5400);
DISPLAY INVISIBLE (-6200 5400);
FORCEPROP 1 LAST PATH I255
J 0
(-6527 5525);
DISPLAY 0.872340 (-6527 5525);
PAINT GREEN (-6527 5525);
DISPLAY INVISIBLE (-6527 5525);
FORCEADD TAP..6
(-6525 5625);
FORCEPROP 3 LASTPIN (-6475 5625) SIG_NAME GMI_CPU1_G0_CPU0_G2_TX_DP<2>
J 0
(-6465 5635);
DISPLAY 0.659574 (-6465 5635);
PAINT MONO (-6465 5635);
DISPLAY INVISIBLE (-6465 5635);
FORCEPROP 1 LASTPIN (-6475 5625) BN 2
J 0
(-6527 5633);
DISPLAY 0.489362 (-6527 5633);
PAINT MONO (-6527 5633);
FORCEPROP 2 LAST CDS_LIB mstr_standard
J 0
(-6525 5625);
DISPLAY INVISIBLE (-6525 5625);
FORCEPROP 1 LAST BODY_TYPE PLUMBING
J 0
(-6525 5575);
DISPLAY 0.574468 (-6525 5575);
PAINT GREEN (-6525 5575);
DISPLAY INVISIBLE (-6525 5575);
FORCEPROP 1 LAST HDL_TAP TRUE
J 0
(-6200 5500);
DISPLAY 0.574468 (-6200 5500);
PAINT GREEN (-6200 5500);
DISPLAY INVISIBLE (-6200 5500);
FORCEPROP 1 LAST PATH I256
J 0
(-6527 5625);
DISPLAY 0.872340 (-6527 5625);
PAINT GREEN (-6527 5625);
DISPLAY INVISIBLE (-6527 5625);
FORCEADD TAP..6
(-6525 5425);
FORCEPROP 3 LASTPIN (-6475 5425) SIG_NAME GMI_CPU1_G0_CPU0_G2_TX_DP<4>
J 0
(-6465 5435);
DISPLAY 0.659574 (-6465 5435);
PAINT MONO (-6465 5435);
DISPLAY INVISIBLE (-6465 5435);
FORCEPROP 1 LASTPIN (-6475 5425) BN 4
J 0
(-6527 5433);
DISPLAY 0.489362 (-6527 5433);
PAINT MONO (-6527 5433);
FORCEPROP 2 LAST CDS_LIB standard
J 0
(-6525 5425);
DISPLAY INVISIBLE (-6525 5425);
FORCEPROP 1 LAST BODY_TYPE PLUMBING
J 0
(-6525 5375);
DISPLAY 0.574468 (-6525 5375);
PAINT GREEN (-6525 5375);
DISPLAY INVISIBLE (-6525 5375);
FORCEPROP 1 LAST HDL_TAP TRUE
J 0
(-6200 5300);
DISPLAY 0.574468 (-6200 5300);
PAINT GREEN (-6200 5300);
DISPLAY INVISIBLE (-6200 5300);
FORCEPROP 1 LAST PATH I257
J 0
(-6527 5425);
DISPLAY 0.872340 (-6527 5425);
PAINT GREEN (-6527 5425);
DISPLAY INVISIBLE (-6527 5425);
FORCEADD TAP..6
(-6675 5575);
FORCEPROP 3 LASTPIN (-6625 5575) SIG_NAME GMI_CPU1_G0_CPU0_G2_TX_DN<2>
J 0
(-6615 5585);
DISPLAY 0.659574 (-6615 5585);
PAINT MONO (-6615 5585);
DISPLAY INVISIBLE (-6615 5585);
FORCEPROP 1 LASTPIN (-6625 5575) BN 2
J 0
(-6677 5583);
DISPLAY 0.489362 (-6677 5583);
PAINT MONO (-6677 5583);
FORCEPROP 2 LAST CDS_LIB standard
J 0
(-6675 5575);
DISPLAY INVISIBLE (-6675 5575);
FORCEPROP 1 LAST BODY_TYPE PLUMBING
J 0
(-6675 5525);
DISPLAY 0.574468 (-6675 5525);
PAINT GREEN (-6675 5525);
DISPLAY INVISIBLE (-6675 5525);
FORCEPROP 1 LAST HDL_TAP TRUE
J 0
(-6350 5450);
DISPLAY 0.574468 (-6350 5450);
PAINT GREEN (-6350 5450);
DISPLAY INVISIBLE (-6350 5450);
FORCEPROP 1 LAST PATH I258
J 0
(-6677 5575);
DISPLAY 0.872340 (-6677 5575);
PAINT GREEN (-6677 5575);
DISPLAY INVISIBLE (-6677 5575);
FORCEADD TAP..6
(-6675 5475);
FORCEPROP 3 LASTPIN (-6625 5475) SIG_NAME GMI_CPU1_G0_CPU0_G2_TX_DN<3>
J 0
(-6615 5485);
DISPLAY 0.659574 (-6615 5485);
PAINT MONO (-6615 5485);
DISPLAY INVISIBLE (-6615 5485);
FORCEPROP 1 LASTPIN (-6625 5475) BN 3
J 0
(-6677 5483);
DISPLAY 0.489362 (-6677 5483);
PAINT MONO (-6677 5483);
FORCEPROP 2 LAST CDS_LIB standard
J 0
(-6675 5475);
DISPLAY INVISIBLE (-6675 5475);
FORCEPROP 1 LAST BODY_TYPE PLUMBING
J 0
(-6675 5425);
DISPLAY 0.574468 (-6675 5425);
PAINT GREEN (-6675 5425);
DISPLAY INVISIBLE (-6675 5425);
FORCEPROP 1 LAST HDL_TAP TRUE
J 0
(-6350 5350);
DISPLAY 0.574468 (-6350 5350);
PAINT GREEN (-6350 5350);
DISPLAY INVISIBLE (-6350 5350);
FORCEPROP 1 LAST PATH I259
J 0
(-6677 5475);
DISPLAY 0.872340 (-6677 5475);
PAINT GREEN (-6677 5475);
DISPLAY INVISIBLE (-6677 5475);
FORCEADD TAP..6
(-6525 5325);
FORCEPROP 3 LASTPIN (-6475 5325) SIG_NAME GMI_CPU1_G0_CPU0_G2_TX_DP<5>
J 0
(-6465 5335);
DISPLAY 0.659574 (-6465 5335);
PAINT MONO (-6465 5335);
DISPLAY INVISIBLE (-6465 5335);
FORCEPROP 1 LASTPIN (-6475 5325) BN 5
J 0
(-6527 5333);
DISPLAY 0.489362 (-6527 5333);
PAINT MONO (-6527 5333);
FORCEPROP 2 LAST CDS_LIB standard
J 0
(-6525 5325);
DISPLAY INVISIBLE (-6525 5325);
FORCEPROP 1 LAST BODY_TYPE PLUMBING
J 0
(-6525 5275);
DISPLAY 0.574468 (-6525 5275);
PAINT GREEN (-6525 5275);
DISPLAY INVISIBLE (-6525 5275);
FORCEPROP 1 LAST HDL_TAP TRUE
J 0
(-6200 5200);
DISPLAY 0.574468 (-6200 5200);
PAINT GREEN (-6200 5200);
DISPLAY INVISIBLE (-6200 5200);
FORCEPROP 1 LAST PATH I260
J 0
(-6527 5325);
DISPLAY 0.872340 (-6527 5325);
PAINT GREEN (-6527 5325);
DISPLAY INVISIBLE (-6527 5325);
FORCEADD TAP..6
(-6525 5225);
FORCEPROP 3 LASTPIN (-6475 5225) SIG_NAME GMI_CPU1_G0_CPU0_G2_TX_DP<6>
J 0
(-6465 5235);
DISPLAY 0.659574 (-6465 5235);
PAINT MONO (-6465 5235);
DISPLAY INVISIBLE (-6465 5235);
FORCEPROP 1 LASTPIN (-6475 5225) BN 6
J 0
(-6527 5233);
DISPLAY 0.489362 (-6527 5233);
PAINT MONO (-6527 5233);
FORCEPROP 2 LAST CDS_LIB standard
J 0
(-6525 5225);
DISPLAY INVISIBLE (-6525 5225);
FORCEPROP 1 LAST BODY_TYPE PLUMBING
J 0
(-6525 5175);
DISPLAY 0.574468 (-6525 5175);
PAINT GREEN (-6525 5175);
DISPLAY INVISIBLE (-6525 5175);
FORCEPROP 1 LAST HDL_TAP TRUE
J 0
(-6200 5100);
DISPLAY 0.574468 (-6200 5100);
PAINT GREEN (-6200 5100);
DISPLAY INVISIBLE (-6200 5100);
FORCEPROP 1 LAST PATH I261
J 0
(-6527 5225);
DISPLAY 0.872340 (-6527 5225);
PAINT GREEN (-6527 5225);
DISPLAY INVISIBLE (-6527 5225);
FORCEADD TAP..6
(-6525 5125);
FORCEPROP 3 LASTPIN (-6475 5125) SIG_NAME GMI_CPU1_G0_CPU0_G2_TX_DP<7>
J 0
(-6465 5135);
DISPLAY 0.659574 (-6465 5135);
PAINT MONO (-6465 5135);
DISPLAY INVISIBLE (-6465 5135);
FORCEPROP 1 LASTPIN (-6475 5125) BN 7
J 0
(-6527 5133);
DISPLAY 0.489362 (-6527 5133);
PAINT MONO (-6527 5133);
FORCEPROP 2 LAST CDS_LIB standard
J 0
(-6525 5125);
DISPLAY INVISIBLE (-6525 5125);
FORCEPROP 1 LAST BODY_TYPE PLUMBING
J 0
(-6525 5075);
DISPLAY 0.574468 (-6525 5075);
PAINT GREEN (-6525 5075);
DISPLAY INVISIBLE (-6525 5075);
FORCEPROP 1 LAST HDL_TAP TRUE
J 0
(-6200 5000);
DISPLAY 0.574468 (-6200 5000);
PAINT GREEN (-6200 5000);
DISPLAY INVISIBLE (-6200 5000);
FORCEPROP 1 LAST PATH I262
J 0
(-6527 5125);
DISPLAY 0.872340 (-6527 5125);
PAINT GREEN (-6527 5125);
DISPLAY INVISIBLE (-6527 5125);
FORCEADD TAP..6
(-6675 5275);
FORCEPROP 3 LASTPIN (-6625 5275) SIG_NAME GMI_CPU1_G0_CPU0_G2_TX_DN<5>
J 0
(-6615 5285);
DISPLAY 0.659574 (-6615 5285);
PAINT MONO (-6615 5285);
DISPLAY INVISIBLE (-6615 5285);
FORCEPROP 1 LASTPIN (-6625 5275) BN 5
J 0
(-6677 5283);
DISPLAY 0.489362 (-6677 5283);
PAINT MONO (-6677 5283);
FORCEPROP 2 LAST CDS_LIB standard
J 0
(-6675 5275);
DISPLAY INVISIBLE (-6675 5275);
FORCEPROP 1 LAST BODY_TYPE PLUMBING
J 0
(-6675 5225);
DISPLAY 0.574468 (-6675 5225);
PAINT GREEN (-6675 5225);
DISPLAY INVISIBLE (-6675 5225);
FORCEPROP 1 LAST HDL_TAP TRUE
J 0
(-6350 5150);
DISPLAY 0.574468 (-6350 5150);
PAINT GREEN (-6350 5150);
DISPLAY INVISIBLE (-6350 5150);
FORCEPROP 1 LAST PATH I263
J 0
(-6677 5275);
DISPLAY 0.872340 (-6677 5275);
PAINT GREEN (-6677 5275);
DISPLAY INVISIBLE (-6677 5275);
FORCEADD TAP..6
(-6675 5375);
FORCEPROP 3 LASTPIN (-6625 5375) SIG_NAME GMI_CPU1_G0_CPU0_G2_TX_DN<4>
J 0
(-6615 5385);
DISPLAY 0.659574 (-6615 5385);
PAINT MONO (-6615 5385);
DISPLAY INVISIBLE (-6615 5385);
FORCEPROP 1 LASTPIN (-6625 5375) BN 4
J 0
(-6677 5383);
DISPLAY 0.489362 (-6677 5383);
PAINT MONO (-6677 5383);
FORCEPROP 2 LAST CDS_LIB standard
J 0
(-6675 5375);
DISPLAY INVISIBLE (-6675 5375);
FORCEPROP 1 LAST BODY_TYPE PLUMBING
J 0
(-6675 5325);
DISPLAY 0.574468 (-6675 5325);
PAINT GREEN (-6675 5325);
DISPLAY INVISIBLE (-6675 5325);
FORCEPROP 1 LAST HDL_TAP TRUE
J 0
(-6350 5250);
DISPLAY 0.574468 (-6350 5250);
PAINT GREEN (-6350 5250);
DISPLAY INVISIBLE (-6350 5250);
FORCEPROP 1 LAST PATH I264
J 0
(-6677 5375);
DISPLAY 0.872340 (-6677 5375);
PAINT GREEN (-6677 5375);
DISPLAY INVISIBLE (-6677 5375);
FORCEADD TAP..6
(-6675 5175);
FORCEPROP 3 LASTPIN (-6625 5175) SIG_NAME GMI_CPU1_G0_CPU0_G2_TX_DN<6>
J 0
(-6615 5185);
DISPLAY 0.659574 (-6615 5185);
PAINT MONO (-6615 5185);
DISPLAY INVISIBLE (-6615 5185);
FORCEPROP 1 LASTPIN (-6625 5175) BN 6
J 0
(-6677 5183);
DISPLAY 0.489362 (-6677 5183);
PAINT MONO (-6677 5183);
FORCEPROP 2 LAST CDS_LIB standard
J 0
(-6675 5175);
DISPLAY INVISIBLE (-6675 5175);
FORCEPROP 1 LAST BODY_TYPE PLUMBING
J 0
(-6675 5125);
DISPLAY 0.574468 (-6675 5125);
PAINT GREEN (-6675 5125);
DISPLAY INVISIBLE (-6675 5125);
FORCEPROP 1 LAST HDL_TAP TRUE
J 0
(-6350 5050);
DISPLAY 0.574468 (-6350 5050);
PAINT GREEN (-6350 5050);
DISPLAY INVISIBLE (-6350 5050);
FORCEPROP 1 LAST PATH I265
J 0
(-6677 5175);
DISPLAY 0.872340 (-6677 5175);
PAINT GREEN (-6677 5175);
DISPLAY INVISIBLE (-6677 5175);
FORCEADD TAP..6
(-6525 5025);
FORCEPROP 3 LASTPIN (-6475 5025) SIG_NAME GMI_CPU1_G0_CPU0_G2_TX_DP<8>
J 0
(-6465 5035);
DISPLAY 0.659574 (-6465 5035);
PAINT MONO (-6465 5035);
DISPLAY INVISIBLE (-6465 5035);
FORCEPROP 1 LASTPIN (-6475 5025) BN 8
J 0
(-6527 5033);
DISPLAY 0.489362 (-6527 5033);
PAINT MONO (-6527 5033);
FORCEPROP 2 LAST CDS_LIB standard
J 0
(-6525 5025);
DISPLAY INVISIBLE (-6525 5025);
FORCEPROP 1 LAST BODY_TYPE PLUMBING
J 0
(-6525 4975);
DISPLAY 0.574468 (-6525 4975);
PAINT GREEN (-6525 4975);
DISPLAY INVISIBLE (-6525 4975);
FORCEPROP 1 LAST HDL_TAP TRUE
J 0
(-6200 4900);
DISPLAY 0.574468 (-6200 4900);
PAINT GREEN (-6200 4900);
DISPLAY INVISIBLE (-6200 4900);
FORCEPROP 1 LAST PATH I266
J 0
(-6527 5025);
DISPLAY 0.872340 (-6527 5025);
PAINT GREEN (-6527 5025);
DISPLAY INVISIBLE (-6527 5025);
FORCEADD TAP..6
(-6525 4925);
FORCEPROP 3 LASTPIN (-6475 4925) SIG_NAME GMI_CPU1_G0_CPU0_G2_TX_DP<9>
J 0
(-6465 4935);
DISPLAY 0.659574 (-6465 4935);
PAINT MONO (-6465 4935);
DISPLAY INVISIBLE (-6465 4935);
FORCEPROP 1 LASTPIN (-6475 4925) BN 9
J 0
(-6527 4933);
DISPLAY 0.489362 (-6527 4933);
PAINT MONO (-6527 4933);
FORCEPROP 2 LAST CDS_LIB standard
J 0
(-6525 4925);
DISPLAY INVISIBLE (-6525 4925);
FORCEPROP 1 LAST BODY_TYPE PLUMBING
J 0
(-6525 4875);
DISPLAY 0.574468 (-6525 4875);
PAINT GREEN (-6525 4875);
DISPLAY INVISIBLE (-6525 4875);
FORCEPROP 1 LAST HDL_TAP TRUE
J 0
(-6200 4800);
DISPLAY 0.574468 (-6200 4800);
PAINT GREEN (-6200 4800);
DISPLAY INVISIBLE (-6200 4800);
FORCEPROP 1 LAST PATH I267
J 0
(-6527 4925);
DISPLAY 0.872340 (-6527 4925);
PAINT GREEN (-6527 4925);
DISPLAY INVISIBLE (-6527 4925);
FORCEADD TAP..6
(-6675 5075);
FORCEPROP 3 LASTPIN (-6625 5075) SIG_NAME GMI_CPU1_G0_CPU0_G2_TX_DN<7>
J 0
(-6615 5085);
DISPLAY 0.659574 (-6615 5085);
PAINT MONO (-6615 5085);
DISPLAY INVISIBLE (-6615 5085);
FORCEPROP 1 LASTPIN (-6625 5075) BN 7
J 0
(-6677 5083);
DISPLAY 0.489362 (-6677 5083);
PAINT MONO (-6677 5083);
FORCEPROP 2 LAST CDS_LIB standard
J 0
(-6675 5075);
DISPLAY INVISIBLE (-6675 5075);
FORCEPROP 1 LAST BODY_TYPE PLUMBING
J 0
(-6675 5025);
DISPLAY 0.574468 (-6675 5025);
PAINT GREEN (-6675 5025);
DISPLAY INVISIBLE (-6675 5025);
FORCEPROP 1 LAST HDL_TAP TRUE
J 0
(-6350 4950);
DISPLAY 0.574468 (-6350 4950);
PAINT GREEN (-6350 4950);
DISPLAY INVISIBLE (-6350 4950);
FORCEPROP 1 LAST PATH I268
J 0
(-6677 5075);
DISPLAY 0.872340 (-6677 5075);
PAINT GREEN (-6677 5075);
DISPLAY INVISIBLE (-6677 5075);
FORCEADD TAP..6
(-6675 4975);
FORCEPROP 3 LASTPIN (-6625 4975) SIG_NAME GMI_CPU1_G0_CPU0_G2_TX_DN<8>
J 0
(-6615 4985);
DISPLAY 0.659574 (-6615 4985);
PAINT MONO (-6615 4985);
DISPLAY INVISIBLE (-6615 4985);
FORCEPROP 1 LASTPIN (-6625 4975) BN 8
J 0
(-6677 4983);
DISPLAY 0.489362 (-6677 4983);
PAINT MONO (-6677 4983);
FORCEPROP 2 LAST CDS_LIB standard
J 0
(-6675 4975);
DISPLAY INVISIBLE (-6675 4975);
FORCEPROP 1 LAST BODY_TYPE PLUMBING
J 0
(-6675 4925);
DISPLAY 0.574468 (-6675 4925);
PAINT GREEN (-6675 4925);
DISPLAY INVISIBLE (-6675 4925);
FORCEPROP 1 LAST HDL_TAP TRUE
J 0
(-6350 4850);
DISPLAY 0.574468 (-6350 4850);
PAINT GREEN (-6350 4850);
DISPLAY INVISIBLE (-6350 4850);
FORCEPROP 1 LAST PATH I269
J 0
(-6677 4975);
DISPLAY 0.872340 (-6677 4975);
PAINT GREEN (-6677 4975);
DISPLAY INVISIBLE (-6677 4975);
FORCEADD TAP..6
(-6675 4875);
FORCEPROP 3 LASTPIN (-6625 4875) SIG_NAME GMI_CPU1_G0_CPU0_G2_TX_DN<9>
J 0
(-6615 4885);
DISPLAY 0.659574 (-6615 4885);
PAINT MONO (-6615 4885);
DISPLAY INVISIBLE (-6615 4885);
FORCEPROP 1 LASTPIN (-6625 4875) BN 9
J 0
(-6677 4883);
DISPLAY 0.489362 (-6677 4883);
PAINT MONO (-6677 4883);
FORCEPROP 2 LAST CDS_LIB standard
J 0
(-6675 4875);
DISPLAY INVISIBLE (-6675 4875);
FORCEPROP 1 LAST BODY_TYPE PLUMBING
J 0
(-6675 4825);
DISPLAY 0.574468 (-6675 4825);
PAINT GREEN (-6675 4825);
DISPLAY INVISIBLE (-6675 4825);
FORCEPROP 1 LAST HDL_TAP TRUE
J 0
(-6350 4750);
DISPLAY 0.574468 (-6350 4750);
PAINT GREEN (-6350 4750);
DISPLAY INVISIBLE (-6350 4750);
FORCEPROP 1 LAST PATH I270
J 0
(-6677 4875);
DISPLAY 0.872340 (-6677 4875);
PAINT GREEN (-6677 4875);
DISPLAY INVISIBLE (-6677 4875);
FORCEADD TAP..6
(-6525 4825);
FORCEPROP 3 LASTPIN (-6475 4825) SIG_NAME GMI_CPU1_G0_CPU0_G2_TX_DP<10>
J 0
(-6465 4835);
DISPLAY 0.659574 (-6465 4835);
PAINT MONO (-6465 4835);
DISPLAY INVISIBLE (-6465 4835);
FORCEPROP 1 LASTPIN (-6475 4825) BN 10
J 0
(-6527 4833);
DISPLAY 0.489362 (-6527 4833);
PAINT MONO (-6527 4833);
FORCEPROP 2 LAST CDS_LIB standard
J 0
(-6525 4825);
DISPLAY INVISIBLE (-6525 4825);
FORCEPROP 1 LAST BODY_TYPE PLUMBING
J 0
(-6525 4775);
DISPLAY 0.574468 (-6525 4775);
PAINT GREEN (-6525 4775);
DISPLAY INVISIBLE (-6525 4775);
FORCEPROP 1 LAST HDL_TAP TRUE
J 0
(-6200 4700);
DISPLAY 0.574468 (-6200 4700);
PAINT GREEN (-6200 4700);
DISPLAY INVISIBLE (-6200 4700);
FORCEPROP 1 LAST PATH I271
J 0
(-6527 4825);
DISPLAY 0.872340 (-6527 4825);
PAINT GREEN (-6527 4825);
DISPLAY INVISIBLE (-6527 4825);
FORCEADD TAP..6
(-6525 4625);
FORCEPROP 3 LASTPIN (-6475 4625) SIG_NAME GMI_CPU1_G0_CPU0_G2_TX_DP<12>
J 0
(-6465 4635);
DISPLAY 0.659574 (-6465 4635);
PAINT MONO (-6465 4635);
DISPLAY INVISIBLE (-6465 4635);
FORCEPROP 1 LASTPIN (-6475 4625) BN 12
J 0
(-6527 4633);
DISPLAY 0.489362 (-6527 4633);
PAINT MONO (-6527 4633);
FORCEPROP 2 LAST CDS_LIB standard
J 0
(-6525 4625);
DISPLAY INVISIBLE (-6525 4625);
FORCEPROP 1 LAST BODY_TYPE PLUMBING
J 0
(-6525 4575);
DISPLAY 0.574468 (-6525 4575);
PAINT GREEN (-6525 4575);
DISPLAY INVISIBLE (-6525 4575);
FORCEPROP 1 LAST HDL_TAP TRUE
J 0
(-6200 4500);
DISPLAY 0.574468 (-6200 4500);
PAINT GREEN (-6200 4500);
DISPLAY INVISIBLE (-6200 4500);
FORCEPROP 1 LAST PATH I272
J 0
(-6527 4625);
DISPLAY 0.872340 (-6527 4625);
PAINT GREEN (-6527 4625);
DISPLAY INVISIBLE (-6527 4625);
FORCEADD TAP..6
(-6525 4725);
FORCEPROP 3 LASTPIN (-6475 4725) SIG_NAME GMI_CPU1_G0_CPU0_G2_TX_DP<11>
J 0
(-6465 4735);
DISPLAY 0.659574 (-6465 4735);
PAINT MONO (-6465 4735);
DISPLAY INVISIBLE (-6465 4735);
FORCEPROP 1 LASTPIN (-6475 4725) BN 11
J 0
(-6527 4733);
DISPLAY 0.489362 (-6527 4733);
PAINT MONO (-6527 4733);
FORCEPROP 2 LAST CDS_LIB standard
J 0
(-6525 4725);
DISPLAY INVISIBLE (-6525 4725);
FORCEPROP 1 LAST BODY_TYPE PLUMBING
J 0
(-6525 4675);
DISPLAY 0.574468 (-6525 4675);
PAINT GREEN (-6525 4675);
DISPLAY INVISIBLE (-6525 4675);
FORCEPROP 1 LAST HDL_TAP TRUE
J 0
(-6200 4600);
DISPLAY 0.574468 (-6200 4600);
PAINT GREEN (-6200 4600);
DISPLAY INVISIBLE (-6200 4600);
FORCEPROP 1 LAST PATH I273
J 0
(-6527 4725);
DISPLAY 0.872340 (-6527 4725);
PAINT GREEN (-6527 4725);
DISPLAY INVISIBLE (-6527 4725);
FORCEADD TAP..6
(-6675 4775);
FORCEPROP 3 LASTPIN (-6625 4775) SIG_NAME GMI_CPU1_G0_CPU0_G2_TX_DN<10>
J 0
(-6615 4785);
DISPLAY 0.659574 (-6615 4785);
PAINT MONO (-6615 4785);
DISPLAY INVISIBLE (-6615 4785);
FORCEPROP 1 LASTPIN (-6625 4775) BN 10
J 0
(-6677 4783);
DISPLAY 0.489362 (-6677 4783);
PAINT MONO (-6677 4783);
FORCEPROP 2 LAST CDS_LIB standard
J 0
(-6675 4775);
DISPLAY INVISIBLE (-6675 4775);
FORCEPROP 1 LAST BODY_TYPE PLUMBING
J 0
(-6675 4725);
DISPLAY 0.574468 (-6675 4725);
PAINT GREEN (-6675 4725);
DISPLAY INVISIBLE (-6675 4725);
FORCEPROP 1 LAST HDL_TAP TRUE
J 0
(-6350 4650);
DISPLAY 0.574468 (-6350 4650);
PAINT GREEN (-6350 4650);
DISPLAY INVISIBLE (-6350 4650);
FORCEPROP 1 LAST PATH I274
J 0
(-6677 4775);
DISPLAY 0.872340 (-6677 4775);
PAINT GREEN (-6677 4775);
DISPLAY INVISIBLE (-6677 4775);
FORCEADD TAP..6
(-6675 4675);
FORCEPROP 3 LASTPIN (-6625 4675) SIG_NAME GMI_CPU1_G0_CPU0_G2_TX_DN<11>
J 0
(-6615 4685);
DISPLAY 0.659574 (-6615 4685);
PAINT MONO (-6615 4685);
DISPLAY INVISIBLE (-6615 4685);
FORCEPROP 1 LASTPIN (-6625 4675) BN 11
J 0
(-6677 4683);
DISPLAY 0.489362 (-6677 4683);
PAINT MONO (-6677 4683);
FORCEPROP 2 LAST CDS_LIB standard
J 0
(-6675 4675);
DISPLAY INVISIBLE (-6675 4675);
FORCEPROP 1 LAST BODY_TYPE PLUMBING
J 0
(-6675 4625);
DISPLAY 0.574468 (-6675 4625);
PAINT GREEN (-6675 4625);
DISPLAY INVISIBLE (-6675 4625);
FORCEPROP 1 LAST HDL_TAP TRUE
J 0
(-6350 4550);
DISPLAY 0.574468 (-6350 4550);
PAINT GREEN (-6350 4550);
DISPLAY INVISIBLE (-6350 4550);
FORCEPROP 1 LAST PATH I275
J 0
(-6677 4675);
DISPLAY 0.872340 (-6677 4675);
PAINT GREEN (-6677 4675);
DISPLAY INVISIBLE (-6677 4675);
FORCEADD TAP..6
(-6525 4525);
FORCEPROP 3 LASTPIN (-6475 4525) SIG_NAME GMI_CPU1_G0_CPU0_G2_TX_DP<13>
J 0
(-6465 4535);
DISPLAY 0.659574 (-6465 4535);
PAINT MONO (-6465 4535);
DISPLAY INVISIBLE (-6465 4535);
FORCEPROP 1 LASTPIN (-6475 4525) BN 13
J 0
(-6527 4533);
DISPLAY 0.489362 (-6527 4533);
PAINT MONO (-6527 4533);
FORCEPROP 2 LAST CDS_LIB standard
J 0
(-6525 4525);
DISPLAY INVISIBLE (-6525 4525);
FORCEPROP 1 LAST BODY_TYPE PLUMBING
J 0
(-6525 4475);
DISPLAY 0.574468 (-6525 4475);
PAINT GREEN (-6525 4475);
DISPLAY INVISIBLE (-6525 4475);
FORCEPROP 1 LAST HDL_TAP TRUE
J 0
(-6200 4400);
DISPLAY 0.574468 (-6200 4400);
PAINT GREEN (-6200 4400);
DISPLAY INVISIBLE (-6200 4400);
FORCEPROP 1 LAST PATH I276
J 0
(-6527 4525);
DISPLAY 0.872340 (-6527 4525);
PAINT GREEN (-6527 4525);
DISPLAY INVISIBLE (-6527 4525);
FORCEADD TAP..6
(-6525 4425);
FORCEPROP 3 LASTPIN (-6475 4425) SIG_NAME GMI_CPU1_G0_CPU0_G2_TX_DP<14>
J 0
(-6465 4435);
DISPLAY 0.659574 (-6465 4435);
PAINT MONO (-6465 4435);
DISPLAY INVISIBLE (-6465 4435);
FORCEPROP 1 LASTPIN (-6475 4425) BN 14
J 0
(-6527 4433);
DISPLAY 0.489362 (-6527 4433);
PAINT MONO (-6527 4433);
FORCEPROP 2 LAST CDS_LIB standard
J 0
(-6525 4425);
DISPLAY INVISIBLE (-6525 4425);
FORCEPROP 1 LAST BODY_TYPE PLUMBING
J 0
(-6525 4375);
DISPLAY 0.574468 (-6525 4375);
PAINT GREEN (-6525 4375);
DISPLAY INVISIBLE (-6525 4375);
FORCEPROP 1 LAST HDL_TAP TRUE
J 0
(-6200 4300);
DISPLAY 0.574468 (-6200 4300);
PAINT GREEN (-6200 4300);
DISPLAY INVISIBLE (-6200 4300);
FORCEPROP 1 LAST PATH I277
J 0
(-6527 4425);
DISPLAY 0.872340 (-6527 4425);
PAINT GREEN (-6527 4425);
DISPLAY INVISIBLE (-6527 4425);
FORCEADD TAP..6
(-6675 4575);
FORCEPROP 3 LASTPIN (-6625 4575) SIG_NAME GMI_CPU1_G0_CPU0_G2_TX_DN<12>
J 0
(-6615 4585);
DISPLAY 0.659574 (-6615 4585);
PAINT MONO (-6615 4585);
DISPLAY INVISIBLE (-6615 4585);
FORCEPROP 1 LASTPIN (-6625 4575) BN 12
J 0
(-6677 4583);
DISPLAY 0.489362 (-6677 4583);
PAINT MONO (-6677 4583);
FORCEPROP 2 LAST CDS_LIB standard
J 0
(-6675 4575);
DISPLAY INVISIBLE (-6675 4575);
FORCEPROP 1 LAST BODY_TYPE PLUMBING
J 0
(-6675 4525);
DISPLAY 0.574468 (-6675 4525);
PAINT GREEN (-6675 4525);
DISPLAY INVISIBLE (-6675 4525);
FORCEPROP 1 LAST HDL_TAP TRUE
J 0
(-6350 4450);
DISPLAY 0.574468 (-6350 4450);
PAINT GREEN (-6350 4450);
DISPLAY INVISIBLE (-6350 4450);
FORCEPROP 1 LAST PATH I278
J 0
(-6677 4575);
DISPLAY 0.872340 (-6677 4575);
PAINT GREEN (-6677 4575);
DISPLAY INVISIBLE (-6677 4575);
FORCEADD TAP..6
(-6675 4475);
FORCEPROP 3 LASTPIN (-6625 4475) SIG_NAME GMI_CPU1_G0_CPU0_G2_TX_DN<13>
J 0
(-6615 4485);
DISPLAY 0.659574 (-6615 4485);
PAINT MONO (-6615 4485);
DISPLAY INVISIBLE (-6615 4485);
FORCEPROP 1 LASTPIN (-6625 4475) BN 13
J 0
(-6677 4483);
DISPLAY 0.489362 (-6677 4483);
PAINT MONO (-6677 4483);
FORCEPROP 2 LAST CDS_LIB standard
J 0
(-6675 4475);
DISPLAY INVISIBLE (-6675 4475);
FORCEPROP 1 LAST BODY_TYPE PLUMBING
J 0
(-6675 4425);
DISPLAY 0.574468 (-6675 4425);
PAINT GREEN (-6675 4425);
DISPLAY INVISIBLE (-6675 4425);
FORCEPROP 1 LAST HDL_TAP TRUE
J 0
(-6350 4350);
DISPLAY 0.574468 (-6350 4350);
PAINT GREEN (-6350 4350);
DISPLAY INVISIBLE (-6350 4350);
FORCEPROP 1 LAST PATH I279
J 0
(-6677 4475);
DISPLAY 0.872340 (-6677 4475);
PAINT GREEN (-6677 4475);
DISPLAY INVISIBLE (-6677 4475);
FORCEADD TAP..6
(-6675 4375);
FORCEPROP 3 LASTPIN (-6625 4375) SIG_NAME GMI_CPU1_G0_CPU0_G2_TX_DN<14>
J 0
(-6615 4385);
DISPLAY 0.659574 (-6615 4385);
PAINT MONO (-6615 4385);
DISPLAY INVISIBLE (-6615 4385);
FORCEPROP 1 LASTPIN (-6625 4375) BN 14
J 0
(-6677 4383);
DISPLAY 0.489362 (-6677 4383);
PAINT MONO (-6677 4383);
FORCEPROP 2 LAST CDS_LIB standard
J 0
(-6675 4375);
DISPLAY INVISIBLE (-6675 4375);
FORCEPROP 1 LAST BODY_TYPE PLUMBING
J 0
(-6675 4325);
DISPLAY 0.574468 (-6675 4325);
PAINT GREEN (-6675 4325);
DISPLAY INVISIBLE (-6675 4325);
FORCEPROP 1 LAST HDL_TAP TRUE
J 0
(-6350 4250);
DISPLAY 0.574468 (-6350 4250);
PAINT GREEN (-6350 4250);
DISPLAY INVISIBLE (-6350 4250);
FORCEPROP 1 LAST PATH I280
J 0
(-6677 4375);
DISPLAY 0.872340 (-6677 4375);
PAINT GREEN (-6677 4375);
DISPLAY INVISIBLE (-6677 4375);
FORCEADD TAP..6
(-6525 4325);
FORCEPROP 3 LASTPIN (-6475 4325) SIG_NAME GMI_CPU1_G0_CPU0_G2_TX_DP<15>
J 0
(-6465 4335);
DISPLAY 0.659574 (-6465 4335);
PAINT MONO (-6465 4335);
DISPLAY INVISIBLE (-6465 4335);
FORCEPROP 1 LASTPIN (-6475 4325) BN 15
J 0
(-6527 4333);
DISPLAY 0.489362 (-6527 4333);
PAINT MONO (-6527 4333);
FORCEPROP 2 LAST CDS_LIB standard
J 0
(-6525 4325);
DISPLAY INVISIBLE (-6525 4325);
FORCEPROP 1 LAST BODY_TYPE PLUMBING
J 0
(-6525 4275);
DISPLAY 0.574468 (-6525 4275);
PAINT GREEN (-6525 4275);
DISPLAY INVISIBLE (-6525 4275);
FORCEPROP 1 LAST HDL_TAP TRUE
J 0
(-6200 4200);
DISPLAY 0.574468 (-6200 4200);
PAINT GREEN (-6200 4200);
DISPLAY INVISIBLE (-6200 4200);
FORCEPROP 1 LAST PATH I281
J 0
(-6527 4325);
DISPLAY 0.872340 (-6527 4325);
PAINT GREEN (-6527 4325);
DISPLAY INVISIBLE (-6527 4325);
FORCEADD TAP..6
(-6675 4275);
FORCEPROP 3 LASTPIN (-6625 4275) SIG_NAME GMI_CPU1_G0_CPU0_G2_TX_DN<15>
J 0
(-6615 4285);
DISPLAY 0.659574 (-6615 4285);
PAINT MONO (-6615 4285);
DISPLAY INVISIBLE (-6615 4285);
FORCEPROP 1 LASTPIN (-6625 4275) BN 15
J 0
(-6677 4283);
DISPLAY 0.489362 (-6677 4283);
PAINT MONO (-6677 4283);
FORCEPROP 2 LAST CDS_LIB standard
J 0
(-6675 4275);
DISPLAY INVISIBLE (-6675 4275);
FORCEPROP 1 LAST BODY_TYPE PLUMBING
J 0
(-6675 4225);
DISPLAY 0.574468 (-6675 4225);
PAINT GREEN (-6675 4225);
DISPLAY INVISIBLE (-6675 4225);
FORCEPROP 1 LAST HDL_TAP TRUE
J 0
(-6350 4150);
DISPLAY 0.574468 (-6350 4150);
PAINT GREEN (-6350 4150);
DISPLAY INVISIBLE (-6350 4150);
FORCEPROP 1 LAST PATH I282
J 0
(-6677 4275);
DISPLAY 0.872340 (-6677 4275);
PAINT GREEN (-6677 4275);
DISPLAY INVISIBLE (-6677 4275);
FORCEADD OFFPAGE..1
(-7725 6000);
FORCEPROP 2 LAST $XR0 49 
J 0
(-7946 6000);
DISPLAY 0.638298 (-7946 6000);
PAINT MONO (-7946 6000);
FORCEPROP 2 LAST CDS_LIB standard
J 0
(-7725 6000);
DISPLAY INVISIBLE (-7725 6000);
FORCEPROP 1 LAST OFFPAGE TRUE
J 0
(-7400 5875);
DISPLAY 0.872340 (-7400 5875);
PAINT GREEN (-7400 5875);
DISPLAY INVISIBLE (-7400 5875);
FORCEPROP 1 LAST COMMENT_BODY TRUE
J 0
(-7600 5900);
DISPLAY 0.872340 (-7600 5900);
PAINT GREEN (-7600 5900);
DISPLAY INVISIBLE (-7600 5900);
FORCEPROP 2 LAST PATH I283
J 0
(-7925 6050);
DISPLAY 1.021277 (-7925 6050);
DISPLAY INVISIBLE (-7925 6050);
FORCEADD OFFPAGE..1
(-7725 6050);
FORCEPROP 2 LAST $XR0 49 
J 0
(-7946 6050);
DISPLAY 0.638298 (-7946 6050);
PAINT MONO (-7946 6050);
FORCEPROP 2 LAST CDS_LIB standard
J 0
(-7725 6050);
DISPLAY INVISIBLE (-7725 6050);
FORCEPROP 1 LAST OFFPAGE TRUE
J 0
(-7400 5925);
DISPLAY 0.872340 (-7400 5925);
PAINT GREEN (-7400 5925);
DISPLAY INVISIBLE (-7400 5925);
FORCEPROP 1 LAST COMMENT_BODY TRUE
J 0
(-7600 5950);
DISPLAY 0.872340 (-7600 5950);
PAINT GREEN (-7600 5950);
DISPLAY INVISIBLE (-7600 5950);
FORCEPROP 2 LAST PATH I284
J 0
(-7925 6100);
DISPLAY 1.021277 (-7925 6100);
DISPLAY INVISIBLE (-7925 6100);
FORCEADD TAP..6
R 2
(-3075 2650);
FORCEPROP 3 LASTPIN (-3125 2650) SIG_NAME P5E_CPU0_G3_TX_DP<3>
J 0
(-3115 2660);
DISPLAY 0.659574 (-3115 2660);
PAINT MONO (-3115 2660);
DISPLAY INVISIBLE (-3115 2660);
FORCEPROP 1 LASTPIN (-3125 2650) BN 3
J 2
(-3073 2658);
DISPLAY 0.489362 (-3073 2658);
PAINT MONO (-3073 2658);
FORCEPROP 2 LAST CDS_LIB standard
J 0
(-3075 2650);
DISPLAY INVISIBLE (-3075 2650);
FORCEPROP 2 LAST BOM_COST IO_SLOT
J 0
(-3575 2750);
DISPLAY 0.829787 (-3575 2750);
DISPLAY INVISIBLE (-3575 2750);
FORCEPROP 2 LAST ROOM RISER1
J 0
(-3575 2700);
DISPLAY 0.829787 (-3575 2700);
PAINT RED (-3575 2700);
DISPLAY INVISIBLE (-3575 2700);
FORCEPROP 1 LAST BODY_TYPE PLUMBING
J 2
(-3075 2600);
DISPLAY 0.702128 (-3075 2600);
PAINT GREEN (-3075 2600);
DISPLAY INVISIBLE (-3075 2600);
FORCEPROP 1 LAST HDL_TAP TRUE
J 2
(-3400 2525);
DISPLAY 0.702128 (-3400 2525);
PAINT GREEN (-3400 2525);
DISPLAY INVISIBLE (-3400 2525);
FORCEPROP 1 LAST PATH I285
J 2
(-3073 2650);
DISPLAY 0.872340 (-3073 2650);
PAINT GREEN (-3073 2650);
DISPLAY INVISIBLE (-3073 2650);
FORCEADD TAP..6
R 2
(-2925 2600);
FORCEPROP 3 LASTPIN (-2975 2600) SIG_NAME P5E_CPU0_G3_TX_DN<3>
J 0
(-2965 2610);
DISPLAY 0.659574 (-2965 2610);
PAINT MONO (-2965 2610);
DISPLAY INVISIBLE (-2965 2610);
FORCEPROP 1 LASTPIN (-2975 2600) BN 3
J 2
(-2923 2608);
DISPLAY 0.489362 (-2923 2608);
PAINT MONO (-2923 2608);
FORCEPROP 2 LAST CDS_LIB standard
J 0
(-2925 2600);
DISPLAY INVISIBLE (-2925 2600);
FORCEPROP 2 LAST BOM_COST IO_SLOT
J 0
(-3425 2700);
DISPLAY 0.829787 (-3425 2700);
DISPLAY INVISIBLE (-3425 2700);
FORCEPROP 2 LAST ROOM RISER1
J 0
(-3425 2650);
DISPLAY 0.829787 (-3425 2650);
PAINT RED (-3425 2650);
DISPLAY INVISIBLE (-3425 2650);
FORCEPROP 1 LAST BODY_TYPE PLUMBING
J 2
(-2925 2550);
DISPLAY 0.702128 (-2925 2550);
PAINT GREEN (-2925 2550);
DISPLAY INVISIBLE (-2925 2550);
FORCEPROP 1 LAST HDL_TAP TRUE
J 2
(-3250 2475);
DISPLAY 0.702128 (-3250 2475);
PAINT GREEN (-3250 2475);
DISPLAY INVISIBLE (-3250 2475);
FORCEPROP 1 LAST PATH I286
J 2
(-2923 2600);
DISPLAY 0.872340 (-2923 2600);
PAINT GREEN (-2923 2600);
DISPLAY INVISIBLE (-2923 2600);
FORCEADD TAP..6
R 2
(-2925 2500);
FORCEPROP 3 LASTPIN (-2975 2500) SIG_NAME P5E_CPU0_G3_TX_DN<4>
J 0
(-2965 2510);
DISPLAY 0.659574 (-2965 2510);
PAINT MONO (-2965 2510);
DISPLAY INVISIBLE (-2965 2510);
FORCEPROP 1 LASTPIN (-2975 2500) BN 4
J 2
(-2923 2508);
DISPLAY 0.489362 (-2923 2508);
PAINT MONO (-2923 2508);
FORCEPROP 2 LAST CDS_LIB standard
J 0
(-2925 2500);
DISPLAY INVISIBLE (-2925 2500);
FORCEPROP 2 LAST BOM_COST IO_SLOT
J 0
(-3425 2600);
DISPLAY 0.829787 (-3425 2600);
DISPLAY INVISIBLE (-3425 2600);
FORCEPROP 2 LAST ROOM RISER1
J 0
(-3425 2550);
DISPLAY 0.829787 (-3425 2550);
PAINT RED (-3425 2550);
DISPLAY INVISIBLE (-3425 2550);
FORCEPROP 1 LAST BODY_TYPE PLUMBING
J 2
(-2925 2450);
DISPLAY 0.702128 (-2925 2450);
PAINT GREEN (-2925 2450);
DISPLAY INVISIBLE (-2925 2450);
FORCEPROP 1 LAST HDL_TAP TRUE
J 2
(-3250 2375);
DISPLAY 0.702128 (-3250 2375);
PAINT GREEN (-3250 2375);
DISPLAY INVISIBLE (-3250 2375);
FORCEPROP 1 LAST PATH I287
J 2
(-2923 2500);
DISPLAY 0.872340 (-2923 2500);
PAINT GREEN (-2923 2500);
DISPLAY INVISIBLE (-2923 2500);
FORCEADD TAP..6
R 2
(-2925 2400);
FORCEPROP 3 LASTPIN (-2975 2400) SIG_NAME P5E_CPU0_G3_TX_DN<5>
J 0
(-2965 2410);
DISPLAY 0.659574 (-2965 2410);
PAINT MONO (-2965 2410);
DISPLAY INVISIBLE (-2965 2410);
FORCEPROP 1 LASTPIN (-2975 2400) BN 5
J 2
(-2923 2408);
DISPLAY 0.489362 (-2923 2408);
PAINT MONO (-2923 2408);
FORCEPROP 2 LAST CDS_LIB standard
J 0
(-2925 2400);
DISPLAY INVISIBLE (-2925 2400);
FORCEPROP 2 LAST BOM_COST IO_SLOT
J 0
(-3425 2500);
DISPLAY 0.829787 (-3425 2500);
DISPLAY INVISIBLE (-3425 2500);
FORCEPROP 2 LAST ROOM RISER1
J 0
(-3425 2450);
DISPLAY 0.829787 (-3425 2450);
PAINT RED (-3425 2450);
DISPLAY INVISIBLE (-3425 2450);
FORCEPROP 1 LAST BODY_TYPE PLUMBING
J 2
(-2925 2350);
DISPLAY 0.702128 (-2925 2350);
PAINT GREEN (-2925 2350);
DISPLAY INVISIBLE (-2925 2350);
FORCEPROP 1 LAST HDL_TAP TRUE
J 2
(-3250 2275);
DISPLAY 0.702128 (-3250 2275);
PAINT GREEN (-3250 2275);
DISPLAY INVISIBLE (-3250 2275);
FORCEPROP 1 LAST PATH I288
J 2
(-2923 2400);
DISPLAY 0.872340 (-2923 2400);
PAINT GREEN (-2923 2400);
DISPLAY INVISIBLE (-2923 2400);
FORCEADD TAP..6
R 2
(-2925 2300);
FORCEPROP 3 LASTPIN (-2975 2300) SIG_NAME P5E_CPU0_G3_TX_DN<6>
J 0
(-2965 2310);
DISPLAY 0.659574 (-2965 2310);
PAINT MONO (-2965 2310);
DISPLAY INVISIBLE (-2965 2310);
FORCEPROP 1 LASTPIN (-2975 2300) BN 6
J 2
(-2923 2308);
DISPLAY 0.489362 (-2923 2308);
PAINT MONO (-2923 2308);
FORCEPROP 2 LAST CDS_LIB standard
J 0
(-2925 2300);
DISPLAY INVISIBLE (-2925 2300);
FORCEPROP 2 LAST BOM_COST IO_SLOT
J 0
(-3425 2400);
DISPLAY 0.829787 (-3425 2400);
DISPLAY INVISIBLE (-3425 2400);
FORCEPROP 2 LAST ROOM RISER1
J 0
(-3425 2350);
DISPLAY 0.829787 (-3425 2350);
PAINT RED (-3425 2350);
DISPLAY INVISIBLE (-3425 2350);
FORCEPROP 1 LAST BODY_TYPE PLUMBING
J 2
(-2925 2250);
DISPLAY 0.702128 (-2925 2250);
PAINT GREEN (-2925 2250);
DISPLAY INVISIBLE (-2925 2250);
FORCEPROP 1 LAST HDL_TAP TRUE
J 2
(-3250 2175);
DISPLAY 0.702128 (-3250 2175);
PAINT GREEN (-3250 2175);
DISPLAY INVISIBLE (-3250 2175);
FORCEPROP 1 LAST PATH I289
J 2
(-2923 2300);
DISPLAY 0.872340 (-2923 2300);
PAINT GREEN (-2923 2300);
DISPLAY INVISIBLE (-2923 2300);
FORCEADD OFFPAGE..2
(-1950 3125);
FORCEPROP 2 LAST $XR0 65 
J 0
(-1761 3125);
DISPLAY 0.638298 (-1761 3125);
PAINT MONO (-1761 3125);
FORCEPROP 2 LAST CDS_LIB standard
J 0
(-1950 3125);
DISPLAY INVISIBLE (-1950 3125);
FORCEPROP 1 LAST OFFPAGE TRUE
J 0
(-1625 3000);
DISPLAY 0.872340 (-1625 3000);
PAINT GREEN (-1625 3000);
DISPLAY INVISIBLE (-1625 3000);
FORCEPROP 1 LAST COMMENT_BODY TRUE
J 0
(-1995 3030);
DISPLAY 0.872340 (-1995 3030);
PAINT GREEN (-1995 3030);
DISPLAY INVISIBLE (-1995 3030);
FORCEPROP 2 LAST PATH I290
J 0
(-1750 3175);
DISPLAY 1.021277 (-1750 3175);
DISPLAY INVISIBLE (-1750 3175);
FORCEADD OFFPAGE..2
(-1950 3175);
FORCEPROP 2 LAST $XR0 65 
J 0
(-1761 3175);
DISPLAY 0.638298 (-1761 3175);
PAINT MONO (-1761 3175);
FORCEPROP 2 LAST CDS_LIB standard
J 0
(-1950 3175);
DISPLAY INVISIBLE (-1950 3175);
FORCEPROP 1 LAST OFFPAGE TRUE
J 0
(-1625 3050);
DISPLAY 0.872340 (-1625 3050);
PAINT GREEN (-1625 3050);
DISPLAY INVISIBLE (-1625 3050);
FORCEPROP 1 LAST COMMENT_BODY TRUE
J 0
(-1995 3080);
DISPLAY 0.872340 (-1995 3080);
PAINT GREEN (-1995 3080);
DISPLAY INVISIBLE (-1995 3080);
FORCEPROP 2 LAST PATH I291
J 0
(-1750 3225);
DISPLAY 1.021277 (-1750 3225);
DISPLAY INVISIBLE (-1750 3225);
FORCEADD TAP..6
R 2
(-2925 2900);
FORCEPROP 3 LASTPIN (-2975 2900) SIG_NAME P5E_CPU0_G3_TX_DN<0>
J 0
(-2965 2910);
DISPLAY 0.659574 (-2965 2910);
PAINT MONO (-2965 2910);
DISPLAY INVISIBLE (-2965 2910);
FORCEPROP 1 LASTPIN (-2975 2900) BN 0
J 2
(-2923 2908);
DISPLAY 0.489362 (-2923 2908);
PAINT MONO (-2923 2908);
FORCEPROP 2 LAST BOM_COST IO_SLOT
J 0
(-3425 3000);
DISPLAY 0.829787 (-3425 3000);
DISPLAY INVISIBLE (-3425 3000);
FORCEPROP 2 LAST CDS_LIB mstr_standard
J 0
(-2925 2900);
DISPLAY INVISIBLE (-2925 2900);
FORCEPROP 2 LAST ROOM RISER1
J 0
(-3425 2950);
DISPLAY 0.829787 (-3425 2950);
PAINT RED (-3425 2950);
DISPLAY INVISIBLE (-3425 2950);
FORCEPROP 1 LAST BODY_TYPE PLUMBING
J 2
(-2925 2850);
DISPLAY 0.702128 (-2925 2850);
PAINT GREEN (-2925 2850);
DISPLAY INVISIBLE (-2925 2850);
FORCEPROP 1 LAST HDL_TAP TRUE
J 2
(-3250 2775);
DISPLAY 0.702128 (-3250 2775);
PAINT GREEN (-3250 2775);
DISPLAY INVISIBLE (-3250 2775);
FORCEPROP 1 LAST PATH I292
J 2
(-2923 2900);
DISPLAY 0.872340 (-2923 2900);
PAINT GREEN (-2923 2900);
DISPLAY INVISIBLE (-2923 2900);
FORCEADD TAP..6
R 2
(-3075 2850);
FORCEPROP 3 LASTPIN (-3125 2850) SIG_NAME P5E_CPU0_G3_TX_DP<1>
J 0
(-3115 2860);
DISPLAY 0.659574 (-3115 2860);
PAINT MONO (-3115 2860);
DISPLAY INVISIBLE (-3115 2860);
FORCEPROP 1 LASTPIN (-3125 2850) BN 1
J 2
(-3073 2858);
DISPLAY 0.489362 (-3073 2858);
PAINT MONO (-3073 2858);
FORCEPROP 2 LAST CDS_LIB mstr_standard
J 0
(-3075 2850);
DISPLAY INVISIBLE (-3075 2850);
FORCEPROP 2 LAST BOM_COST IO_SLOT
J 0
(-3575 2950);
DISPLAY 0.829787 (-3575 2950);
DISPLAY INVISIBLE (-3575 2950);
FORCEPROP 2 LAST ROOM RISER1
J 0
(-3575 2900);
DISPLAY 0.829787 (-3575 2900);
PAINT RED (-3575 2900);
DISPLAY INVISIBLE (-3575 2900);
FORCEPROP 1 LAST BODY_TYPE PLUMBING
J 2
(-3075 2800);
DISPLAY 0.702128 (-3075 2800);
PAINT GREEN (-3075 2800);
DISPLAY INVISIBLE (-3075 2800);
FORCEPROP 1 LAST HDL_TAP TRUE
J 2
(-3400 2725);
DISPLAY 0.702128 (-3400 2725);
PAINT GREEN (-3400 2725);
DISPLAY INVISIBLE (-3400 2725);
FORCEPROP 1 LAST PATH I293
J 2
(-3073 2850);
DISPLAY 0.872340 (-3073 2850);
PAINT GREEN (-3073 2850);
DISPLAY INVISIBLE (-3073 2850);
FORCEADD TAP..6
R 2
(-3075 2950);
FORCEPROP 3 LASTPIN (-3125 2950) SIG_NAME P5E_CPU0_G3_TX_DP<0>
J 0
(-3115 2960);
DISPLAY 0.659574 (-3115 2960);
PAINT MONO (-3115 2960);
DISPLAY INVISIBLE (-3115 2960);
FORCEPROP 1 LASTPIN (-3125 2950) BN 0
J 2
(-3073 2958);
DISPLAY 0.489362 (-3073 2958);
PAINT MONO (-3073 2958);
FORCEPROP 2 LAST CDS_LIB mstr_standard
J 0
(-3075 2950);
DISPLAY INVISIBLE (-3075 2950);
FORCEPROP 2 LAST BOM_COST IO_SLOT
J 0
(-3575 3050);
DISPLAY 0.829787 (-3575 3050);
DISPLAY INVISIBLE (-3575 3050);
FORCEPROP 2 LAST ROOM RISER1
J 0
(-3575 3000);
DISPLAY 0.829787 (-3575 3000);
PAINT RED (-3575 3000);
DISPLAY INVISIBLE (-3575 3000);
FORCEPROP 1 LAST BODY_TYPE PLUMBING
J 2
(-3075 2900);
DISPLAY 0.702128 (-3075 2900);
PAINT GREEN (-3075 2900);
DISPLAY INVISIBLE (-3075 2900);
FORCEPROP 1 LAST HDL_TAP TRUE
J 2
(-3400 2825);
DISPLAY 0.702128 (-3400 2825);
PAINT GREEN (-3400 2825);
DISPLAY INVISIBLE (-3400 2825);
FORCEPROP 1 LAST PATH I294
J 2
(-3073 2950);
DISPLAY 0.872340 (-3073 2950);
PAINT GREEN (-3073 2950);
DISPLAY INVISIBLE (-3073 2950);
FORCEADD TAP..6
R 2
(-2925 2700);
FORCEPROP 3 LASTPIN (-2975 2700) SIG_NAME P5E_CPU0_G3_TX_DN<2>
J 0
(-2965 2710);
DISPLAY 0.659574 (-2965 2710);
PAINT MONO (-2965 2710);
DISPLAY INVISIBLE (-2965 2710);
FORCEPROP 1 LASTPIN (-2975 2700) BN 2
J 2
(-2923 2708);
DISPLAY 0.489362 (-2923 2708);
PAINT MONO (-2923 2708);
FORCEPROP 2 LAST CDS_LIB standard
J 0
(-2925 2700);
DISPLAY INVISIBLE (-2925 2700);
FORCEPROP 2 LAST BOM_COST IO_SLOT
J 0
(-3425 2800);
DISPLAY 0.829787 (-3425 2800);
DISPLAY INVISIBLE (-3425 2800);
FORCEPROP 2 LAST ROOM RISER1
J 0
(-3425 2750);
DISPLAY 0.829787 (-3425 2750);
PAINT RED (-3425 2750);
DISPLAY INVISIBLE (-3425 2750);
FORCEPROP 1 LAST BODY_TYPE PLUMBING
J 2
(-2925 2650);
DISPLAY 0.702128 (-2925 2650);
PAINT GREEN (-2925 2650);
DISPLAY INVISIBLE (-2925 2650);
FORCEPROP 1 LAST HDL_TAP TRUE
J 2
(-3250 2575);
DISPLAY 0.702128 (-3250 2575);
PAINT GREEN (-3250 2575);
DISPLAY INVISIBLE (-3250 2575);
FORCEPROP 1 LAST PATH I295
J 2
(-2923 2700);
DISPLAY 0.872340 (-2923 2700);
PAINT GREEN (-2923 2700);
DISPLAY INVISIBLE (-2923 2700);
FORCEADD TAP..6
R 2
(-2925 2800);
FORCEPROP 3 LASTPIN (-2975 2800) SIG_NAME P5E_CPU0_G3_TX_DN<1>
J 0
(-2965 2810);
DISPLAY 0.659574 (-2965 2810);
PAINT MONO (-2965 2810);
DISPLAY INVISIBLE (-2965 2810);
FORCEPROP 1 LASTPIN (-2975 2800) BN 1
J 2
(-2923 2808);
DISPLAY 0.489362 (-2923 2808);
PAINT MONO (-2923 2808);
FORCEPROP 2 LAST CDS_LIB mstr_standard
J 0
(-2925 2800);
DISPLAY INVISIBLE (-2925 2800);
FORCEPROP 2 LAST BOM_COST IO_SLOT
J 0
(-3425 2900);
DISPLAY 0.829787 (-3425 2900);
DISPLAY INVISIBLE (-3425 2900);
FORCEPROP 2 LAST ROOM RISER1
J 0
(-3425 2850);
DISPLAY 0.829787 (-3425 2850);
PAINT RED (-3425 2850);
DISPLAY INVISIBLE (-3425 2850);
FORCEPROP 1 LAST BODY_TYPE PLUMBING
J 2
(-2925 2750);
DISPLAY 0.702128 (-2925 2750);
PAINT GREEN (-2925 2750);
DISPLAY INVISIBLE (-2925 2750);
FORCEPROP 1 LAST HDL_TAP TRUE
J 2
(-3250 2675);
DISPLAY 0.702128 (-3250 2675);
PAINT GREEN (-3250 2675);
DISPLAY INVISIBLE (-3250 2675);
FORCEPROP 1 LAST PATH I296
J 2
(-2923 2800);
DISPLAY 0.872340 (-2923 2800);
PAINT GREEN (-2923 2800);
DISPLAY INVISIBLE (-2923 2800);
FORCEADD TAP..6
R 2
(-3075 2750);
FORCEPROP 3 LASTPIN (-3125 2750) SIG_NAME P5E_CPU0_G3_TX_DP<2>
J 0
(-3115 2760);
DISPLAY 0.659574 (-3115 2760);
PAINT MONO (-3115 2760);
DISPLAY INVISIBLE (-3115 2760);
FORCEPROP 1 LASTPIN (-3125 2750) BN 2
J 2
(-3073 2758);
DISPLAY 0.489362 (-3073 2758);
PAINT MONO (-3073 2758);
FORCEPROP 2 LAST CDS_LIB standard
J 0
(-3075 2750);
DISPLAY INVISIBLE (-3075 2750);
FORCEPROP 2 LAST BOM_COST IO_SLOT
J 0
(-3575 2850);
DISPLAY 0.829787 (-3575 2850);
DISPLAY INVISIBLE (-3575 2850);
FORCEPROP 2 LAST ROOM RISER1
J 0
(-3575 2800);
DISPLAY 0.829787 (-3575 2800);
PAINT RED (-3575 2800);
DISPLAY INVISIBLE (-3575 2800);
FORCEPROP 1 LAST BODY_TYPE PLUMBING
J 2
(-3075 2700);
DISPLAY 0.702128 (-3075 2700);
PAINT GREEN (-3075 2700);
DISPLAY INVISIBLE (-3075 2700);
FORCEPROP 1 LAST HDL_TAP TRUE
J 2
(-3400 2625);
DISPLAY 0.702128 (-3400 2625);
PAINT GREEN (-3400 2625);
DISPLAY INVISIBLE (-3400 2625);
FORCEPROP 1 LAST PATH I297
J 2
(-3073 2750);
DISPLAY 0.872340 (-3073 2750);
PAINT GREEN (-3073 2750);
DISPLAY INVISIBLE (-3073 2750);
FORCEADD TAP..6
R 2
(-3075 2350);
FORCEPROP 3 LASTPIN (-3125 2350) SIG_NAME P5E_CPU0_G3_TX_DP<6>
J 0
(-3115 2360);
DISPLAY 0.659574 (-3115 2360);
PAINT MONO (-3115 2360);
DISPLAY INVISIBLE (-3115 2360);
FORCEPROP 1 LASTPIN (-3125 2350) BN 6
J 2
(-3073 2358);
DISPLAY 0.489362 (-3073 2358);
PAINT MONO (-3073 2358);
FORCEPROP 2 LAST CDS_LIB standard
J 0
(-3075 2350);
DISPLAY INVISIBLE (-3075 2350);
FORCEPROP 2 LAST BOM_COST IO_SLOT
J 0
(-3575 2450);
DISPLAY 0.829787 (-3575 2450);
DISPLAY INVISIBLE (-3575 2450);
FORCEPROP 2 LAST ROOM RISER1
J 0
(-3575 2400);
DISPLAY 0.829787 (-3575 2400);
PAINT RED (-3575 2400);
DISPLAY INVISIBLE (-3575 2400);
FORCEPROP 1 LAST BODY_TYPE PLUMBING
J 2
(-3075 2300);
DISPLAY 0.702128 (-3075 2300);
PAINT GREEN (-3075 2300);
DISPLAY INVISIBLE (-3075 2300);
FORCEPROP 1 LAST HDL_TAP TRUE
J 2
(-3400 2225);
DISPLAY 0.702128 (-3400 2225);
PAINT GREEN (-3400 2225);
DISPLAY INVISIBLE (-3400 2225);
FORCEPROP 1 LAST PATH I298
J 2
(-3073 2350);
DISPLAY 0.872340 (-3073 2350);
PAINT GREEN (-3073 2350);
DISPLAY INVISIBLE (-3073 2350);
FORCEADD TAP..6
R 2
(-3075 2550);
FORCEPROP 3 LASTPIN (-3125 2550) SIG_NAME P5E_CPU0_G3_TX_DP<4>
J 0
(-3115 2560);
DISPLAY 0.659574 (-3115 2560);
PAINT MONO (-3115 2560);
DISPLAY INVISIBLE (-3115 2560);
FORCEPROP 1 LASTPIN (-3125 2550) BN 4
J 2
(-3073 2558);
DISPLAY 0.489362 (-3073 2558);
PAINT MONO (-3073 2558);
FORCEPROP 2 LAST CDS_LIB standard
J 0
(-3075 2550);
DISPLAY INVISIBLE (-3075 2550);
FORCEPROP 2 LAST BOM_COST IO_SLOT
J 0
(-3575 2650);
DISPLAY 0.829787 (-3575 2650);
DISPLAY INVISIBLE (-3575 2650);
FORCEPROP 2 LAST ROOM RISER1
J 0
(-3575 2600);
DISPLAY 0.829787 (-3575 2600);
PAINT RED (-3575 2600);
DISPLAY INVISIBLE (-3575 2600);
FORCEPROP 1 LAST BODY_TYPE PLUMBING
J 2
(-3075 2500);
DISPLAY 0.702128 (-3075 2500);
PAINT GREEN (-3075 2500);
DISPLAY INVISIBLE (-3075 2500);
FORCEPROP 1 LAST HDL_TAP TRUE
J 2
(-3400 2425);
DISPLAY 0.702128 (-3400 2425);
PAINT GREEN (-3400 2425);
DISPLAY INVISIBLE (-3400 2425);
FORCEPROP 1 LAST PATH I299
J 2
(-3073 2550);
DISPLAY 0.872340 (-3073 2550);
PAINT GREEN (-3073 2550);
DISPLAY INVISIBLE (-3073 2550);
FORCEADD TAP..6
R 2
(-3075 2450);
FORCEPROP 3 LASTPIN (-3125 2450) SIG_NAME P5E_CPU0_G3_TX_DP<5>
J 0
(-3115 2460);
DISPLAY 0.659574 (-3115 2460);
PAINT MONO (-3115 2460);
DISPLAY INVISIBLE (-3115 2460);
FORCEPROP 1 LASTPIN (-3125 2450) BN 5
J 2
(-3073 2458);
DISPLAY 0.489362 (-3073 2458);
PAINT MONO (-3073 2458);
FORCEPROP 2 LAST CDS_LIB standard
J 0
(-3075 2450);
DISPLAY INVISIBLE (-3075 2450);
FORCEPROP 2 LAST BOM_COST IO_SLOT
J 0
(-3575 2550);
DISPLAY 0.829787 (-3575 2550);
DISPLAY INVISIBLE (-3575 2550);
FORCEPROP 2 LAST ROOM RISER1
J 0
(-3575 2500);
DISPLAY 0.829787 (-3575 2500);
PAINT RED (-3575 2500);
DISPLAY INVISIBLE (-3575 2500);
FORCEPROP 1 LAST BODY_TYPE PLUMBING
J 2
(-3075 2400);
DISPLAY 0.702128 (-3075 2400);
PAINT GREEN (-3075 2400);
DISPLAY INVISIBLE (-3075 2400);
FORCEPROP 1 LAST HDL_TAP TRUE
J 2
(-3400 2325);
DISPLAY 0.702128 (-3400 2325);
PAINT GREEN (-3400 2325);
DISPLAY INVISIBLE (-3400 2325);
FORCEPROP 1 LAST PATH I300
J 2
(-3073 2450);
DISPLAY 0.872340 (-3073 2450);
PAINT GREEN (-3073 2450);
DISPLAY INVISIBLE (-3073 2450);
FORCEADD TAP..6
R 2
(-2925 2200);
FORCEPROP 3 LASTPIN (-2975 2200) SIG_NAME P5E_CPU0_G3_TX_DN<7>
J 0
(-2965 2210);
DISPLAY 0.659574 (-2965 2210);
PAINT MONO (-2965 2210);
DISPLAY INVISIBLE (-2965 2210);
FORCEPROP 1 LASTPIN (-2975 2200) BN 7
J 2
(-2923 2208);
DISPLAY 0.489362 (-2923 2208);
PAINT MONO (-2923 2208);
FORCEPROP 2 LAST CDS_LIB standard
J 0
(-2925 2200);
DISPLAY INVISIBLE (-2925 2200);
FORCEPROP 2 LAST BOM_COST IO_SLOT
J 0
(-3425 2300);
DISPLAY 0.829787 (-3425 2300);
DISPLAY INVISIBLE (-3425 2300);
FORCEPROP 2 LAST ROOM RISER1
J 0
(-3425 2250);
DISPLAY 0.829787 (-3425 2250);
PAINT RED (-3425 2250);
DISPLAY INVISIBLE (-3425 2250);
FORCEPROP 1 LAST BODY_TYPE PLUMBING
J 2
(-2925 2150);
DISPLAY 0.702128 (-2925 2150);
PAINT GREEN (-2925 2150);
DISPLAY INVISIBLE (-2925 2150);
FORCEPROP 1 LAST HDL_TAP TRUE
J 2
(-3250 2075);
DISPLAY 0.702128 (-3250 2075);
PAINT GREEN (-3250 2075);
DISPLAY INVISIBLE (-3250 2075);
FORCEPROP 1 LAST PATH I301
J 2
(-2923 2200);
DISPLAY 0.872340 (-2923 2200);
PAINT GREEN (-2923 2200);
DISPLAY INVISIBLE (-2923 2200);
FORCEADD TAP..6
R 2
(-2925 2100);
FORCEPROP 3 LASTPIN (-2975 2100) SIG_NAME P5E_CPU0_G3_TX_DN<8>
J 0
(-2965 2110);
DISPLAY 0.659574 (-2965 2110);
PAINT MONO (-2965 2110);
DISPLAY INVISIBLE (-2965 2110);
FORCEPROP 1 LASTPIN (-2975 2100) BN 8
J 2
(-2923 2108);
DISPLAY 0.489362 (-2923 2108);
PAINT MONO (-2923 2108);
FORCEPROP 2 LAST CDS_LIB standard
J 0
(-2925 2100);
DISPLAY INVISIBLE (-2925 2100);
FORCEPROP 2 LAST BOM_COST IO_SLOT
J 0
(-3425 2200);
DISPLAY 0.829787 (-3425 2200);
DISPLAY INVISIBLE (-3425 2200);
FORCEPROP 2 LAST ROOM RISER1
J 0
(-3425 2150);
DISPLAY 0.829787 (-3425 2150);
PAINT RED (-3425 2150);
DISPLAY INVISIBLE (-3425 2150);
FORCEPROP 1 LAST BODY_TYPE PLUMBING
J 2
(-2925 2050);
DISPLAY 0.702128 (-2925 2050);
PAINT GREEN (-2925 2050);
DISPLAY INVISIBLE (-2925 2050);
FORCEPROP 1 LAST HDL_TAP TRUE
J 2
(-3250 1975);
DISPLAY 0.702128 (-3250 1975);
PAINT GREEN (-3250 1975);
DISPLAY INVISIBLE (-3250 1975);
FORCEPROP 1 LAST PATH I302
J 2
(-2923 2100);
DISPLAY 0.872340 (-2923 2100);
PAINT GREEN (-2923 2100);
DISPLAY INVISIBLE (-2923 2100);
FORCEADD TAP..6
R 2
(-3075 2250);
FORCEPROP 3 LASTPIN (-3125 2250) SIG_NAME P5E_CPU0_G3_TX_DP<7>
J 0
(-3115 2260);
DISPLAY 0.659574 (-3115 2260);
PAINT MONO (-3115 2260);
DISPLAY INVISIBLE (-3115 2260);
FORCEPROP 1 LASTPIN (-3125 2250) BN 7
J 2
(-3073 2258);
DISPLAY 0.489362 (-3073 2258);
PAINT MONO (-3073 2258);
FORCEPROP 2 LAST CDS_LIB standard
J 0
(-3075 2250);
DISPLAY INVISIBLE (-3075 2250);
FORCEPROP 2 LAST BOM_COST IO_SLOT
J 0
(-3575 2350);
DISPLAY 0.829787 (-3575 2350);
DISPLAY INVISIBLE (-3575 2350);
FORCEPROP 2 LAST ROOM RISER1
J 0
(-3575 2300);
DISPLAY 0.829787 (-3575 2300);
PAINT RED (-3575 2300);
DISPLAY INVISIBLE (-3575 2300);
FORCEPROP 1 LAST BODY_TYPE PLUMBING
J 2
(-3075 2200);
DISPLAY 0.702128 (-3075 2200);
PAINT GREEN (-3075 2200);
DISPLAY INVISIBLE (-3075 2200);
FORCEPROP 1 LAST HDL_TAP TRUE
J 2
(-3400 2125);
DISPLAY 0.702128 (-3400 2125);
PAINT GREEN (-3400 2125);
DISPLAY INVISIBLE (-3400 2125);
FORCEPROP 1 LAST PATH I303
J 2
(-3073 2250);
DISPLAY 0.872340 (-3073 2250);
PAINT GREEN (-3073 2250);
DISPLAY INVISIBLE (-3073 2250);
FORCEADD TAP..6
R 2
(-3075 2150);
FORCEPROP 3 LASTPIN (-3125 2150) SIG_NAME P5E_CPU0_G3_TX_DP<8>
J 0
(-3115 2160);
DISPLAY 0.659574 (-3115 2160);
PAINT MONO (-3115 2160);
DISPLAY INVISIBLE (-3115 2160);
FORCEPROP 1 LASTPIN (-3125 2150) BN 8
J 2
(-3073 2158);
DISPLAY 0.489362 (-3073 2158);
PAINT MONO (-3073 2158);
FORCEPROP 2 LAST CDS_LIB standard
J 0
(-3075 2150);
DISPLAY INVISIBLE (-3075 2150);
FORCEPROP 2 LAST BOM_COST IO_SLOT
J 0
(-3575 2250);
DISPLAY 0.829787 (-3575 2250);
DISPLAY INVISIBLE (-3575 2250);
FORCEPROP 2 LAST ROOM RISER1
J 0
(-3575 2200);
DISPLAY 0.829787 (-3575 2200);
PAINT RED (-3575 2200);
DISPLAY INVISIBLE (-3575 2200);
FORCEPROP 1 LAST BODY_TYPE PLUMBING
J 2
(-3075 2100);
DISPLAY 0.702128 (-3075 2100);
PAINT GREEN (-3075 2100);
DISPLAY INVISIBLE (-3075 2100);
FORCEPROP 1 LAST HDL_TAP TRUE
J 2
(-3400 2025);
DISPLAY 0.702128 (-3400 2025);
PAINT GREEN (-3400 2025);
DISPLAY INVISIBLE (-3400 2025);
FORCEPROP 1 LAST PATH I304
J 2
(-3073 2150);
DISPLAY 0.872340 (-3073 2150);
PAINT GREEN (-3073 2150);
DISPLAY INVISIBLE (-3073 2150);
FORCEADD TAP..6
R 2
(-3075 2050);
FORCEPROP 3 LASTPIN (-3125 2050) SIG_NAME P5E_CPU0_G3_TX_DP<9>
J 0
(-3115 2060);
DISPLAY 0.659574 (-3115 2060);
PAINT MONO (-3115 2060);
DISPLAY INVISIBLE (-3115 2060);
FORCEPROP 1 LASTPIN (-3125 2050) BN 9
J 2
(-3073 2058);
DISPLAY 0.489362 (-3073 2058);
PAINT MONO (-3073 2058);
FORCEPROP 2 LAST CDS_LIB standard
J 0
(-3075 2050);
DISPLAY INVISIBLE (-3075 2050);
FORCEPROP 2 LAST BOM_COST IO_SLOT
J 0
(-3575 2150);
DISPLAY 0.829787 (-3575 2150);
DISPLAY INVISIBLE (-3575 2150);
FORCEPROP 2 LAST ROOM RISER1
J 0
(-3575 2100);
DISPLAY 0.829787 (-3575 2100);
PAINT RED (-3575 2100);
DISPLAY INVISIBLE (-3575 2100);
FORCEPROP 1 LAST BODY_TYPE PLUMBING
J 2
(-3075 2000);
DISPLAY 0.702128 (-3075 2000);
PAINT GREEN (-3075 2000);
DISPLAY INVISIBLE (-3075 2000);
FORCEPROP 1 LAST HDL_TAP TRUE
J 2
(-3400 1925);
DISPLAY 0.702128 (-3400 1925);
PAINT GREEN (-3400 1925);
DISPLAY INVISIBLE (-3400 1925);
FORCEPROP 1 LAST PATH I305
J 2
(-3073 2050);
DISPLAY 0.872340 (-3073 2050);
PAINT GREEN (-3073 2050);
DISPLAY INVISIBLE (-3073 2050);
FORCEADD TAP..6
R 2
(-2925 2000);
FORCEPROP 3 LASTPIN (-2975 2000) SIG_NAME P5E_CPU0_G3_TX_DN<9>
J 0
(-2965 2010);
DISPLAY 0.659574 (-2965 2010);
PAINT MONO (-2965 2010);
DISPLAY INVISIBLE (-2965 2010);
FORCEPROP 1 LASTPIN (-2975 2000) BN 9
J 2
(-2923 2008);
DISPLAY 0.489362 (-2923 2008);
PAINT MONO (-2923 2008);
FORCEPROP 2 LAST CDS_LIB standard
J 0
(-2925 2000);
DISPLAY INVISIBLE (-2925 2000);
FORCEPROP 2 LAST BOM_COST IO_SLOT
J 0
(-3425 2100);
DISPLAY 0.829787 (-3425 2100);
DISPLAY INVISIBLE (-3425 2100);
FORCEPROP 2 LAST ROOM RISER1
J 0
(-3425 2050);
DISPLAY 0.829787 (-3425 2050);
PAINT RED (-3425 2050);
DISPLAY INVISIBLE (-3425 2050);
FORCEPROP 1 LAST BODY_TYPE PLUMBING
J 2
(-2925 1950);
DISPLAY 0.702128 (-2925 1950);
PAINT GREEN (-2925 1950);
DISPLAY INVISIBLE (-2925 1950);
FORCEPROP 1 LAST HDL_TAP TRUE
J 2
(-3250 1875);
DISPLAY 0.702128 (-3250 1875);
PAINT GREEN (-3250 1875);
DISPLAY INVISIBLE (-3250 1875);
FORCEPROP 1 LAST PATH I306
J 2
(-2923 2000);
DISPLAY 0.872340 (-2923 2000);
PAINT GREEN (-2923 2000);
DISPLAY INVISIBLE (-2923 2000);
FORCEADD TAP..6
R 2
(-2925 1800);
FORCEPROP 3 LASTPIN (-2975 1800) SIG_NAME P5E_CPU0_G3_TX_DN<11>
J 0
(-2965 1810);
DISPLAY 0.659574 (-2965 1810);
PAINT MONO (-2965 1810);
DISPLAY INVISIBLE (-2965 1810);
FORCEPROP 1 LASTPIN (-2975 1800) BN 11
J 2
(-2923 1808);
DISPLAY 0.489362 (-2923 1808);
PAINT MONO (-2923 1808);
FORCEPROP 2 LAST CDS_LIB standard
J 0
(-2925 1800);
DISPLAY INVISIBLE (-2925 1800);
FORCEPROP 2 LAST BOM_COST IO_SLOT
J 0
(-3425 1900);
DISPLAY 0.829787 (-3425 1900);
DISPLAY INVISIBLE (-3425 1900);
FORCEPROP 2 LAST ROOM RISER1
J 0
(-3425 1850);
DISPLAY 0.829787 (-3425 1850);
PAINT RED (-3425 1850);
DISPLAY INVISIBLE (-3425 1850);
FORCEPROP 1 LAST BODY_TYPE PLUMBING
J 2
(-2925 1750);
DISPLAY 0.702128 (-2925 1750);
PAINT GREEN (-2925 1750);
DISPLAY INVISIBLE (-2925 1750);
FORCEPROP 1 LAST HDL_TAP TRUE
J 2
(-3250 1675);
DISPLAY 0.702128 (-3250 1675);
PAINT GREEN (-3250 1675);
DISPLAY INVISIBLE (-3250 1675);
FORCEPROP 1 LAST PATH I307
J 2
(-2923 1800);
DISPLAY 0.872340 (-2923 1800);
PAINT GREEN (-2923 1800);
DISPLAY INVISIBLE (-2923 1800);
FORCEADD TAP..6
R 2
(-2925 1900);
FORCEPROP 3 LASTPIN (-2975 1900) SIG_NAME P5E_CPU0_G3_TX_DN<10>
J 0
(-2965 1910);
DISPLAY 0.659574 (-2965 1910);
PAINT MONO (-2965 1910);
DISPLAY INVISIBLE (-2965 1910);
FORCEPROP 1 LASTPIN (-2975 1900) BN 10
J 2
(-2923 1908);
DISPLAY 0.489362 (-2923 1908);
PAINT MONO (-2923 1908);
FORCEPROP 2 LAST CDS_LIB standard
J 0
(-2925 1900);
DISPLAY INVISIBLE (-2925 1900);
FORCEPROP 2 LAST BOM_COST IO_SLOT
J 0
(-3425 2000);
DISPLAY 0.829787 (-3425 2000);
DISPLAY INVISIBLE (-3425 2000);
FORCEPROP 2 LAST ROOM RISER1
J 0
(-3425 1950);
DISPLAY 0.829787 (-3425 1950);
PAINT RED (-3425 1950);
DISPLAY INVISIBLE (-3425 1950);
FORCEPROP 1 LAST BODY_TYPE PLUMBING
J 2
(-2925 1850);
DISPLAY 0.702128 (-2925 1850);
PAINT GREEN (-2925 1850);
DISPLAY INVISIBLE (-2925 1850);
FORCEPROP 1 LAST HDL_TAP TRUE
J 2
(-3250 1775);
DISPLAY 0.702128 (-3250 1775);
PAINT GREEN (-3250 1775);
DISPLAY INVISIBLE (-3250 1775);
FORCEPROP 1 LAST PATH I308
J 2
(-2923 1900);
DISPLAY 0.872340 (-2923 1900);
PAINT GREEN (-2923 1900);
DISPLAY INVISIBLE (-2923 1900);
FORCEADD TAP..6
R 2
(-3075 1950);
FORCEPROP 3 LASTPIN (-3125 1950) SIG_NAME P5E_CPU0_G3_TX_DP<10>
J 0
(-3115 1960);
DISPLAY 0.659574 (-3115 1960);
PAINT MONO (-3115 1960);
DISPLAY INVISIBLE (-3115 1960);
FORCEPROP 1 LASTPIN (-3125 1950) BN 10
J 2
(-3073 1958);
DISPLAY 0.489362 (-3073 1958);
PAINT MONO (-3073 1958);
FORCEPROP 2 LAST CDS_LIB standard
J 0
(-3075 1950);
DISPLAY INVISIBLE (-3075 1950);
FORCEPROP 2 LAST BOM_COST IO_SLOT
J 0
(-3575 2050);
DISPLAY 0.829787 (-3575 2050);
DISPLAY INVISIBLE (-3575 2050);
FORCEPROP 2 LAST ROOM RISER1
J 0
(-3575 2000);
DISPLAY 0.829787 (-3575 2000);
PAINT RED (-3575 2000);
DISPLAY INVISIBLE (-3575 2000);
FORCEPROP 1 LAST BODY_TYPE PLUMBING
J 2
(-3075 1900);
DISPLAY 0.702128 (-3075 1900);
PAINT GREEN (-3075 1900);
DISPLAY INVISIBLE (-3075 1900);
FORCEPROP 1 LAST HDL_TAP TRUE
J 2
(-3400 1825);
DISPLAY 0.702128 (-3400 1825);
PAINT GREEN (-3400 1825);
DISPLAY INVISIBLE (-3400 1825);
FORCEPROP 1 LAST PATH I309
J 2
(-3073 1950);
DISPLAY 0.872340 (-3073 1950);
PAINT GREEN (-3073 1950);
DISPLAY INVISIBLE (-3073 1950);
FORCEADD TAP..6
R 2
(-3075 1850);
FORCEPROP 3 LASTPIN (-3125 1850) SIG_NAME P5E_CPU0_G3_TX_DP<11>
J 0
(-3115 1860);
DISPLAY 0.659574 (-3115 1860);
PAINT MONO (-3115 1860);
DISPLAY INVISIBLE (-3115 1860);
FORCEPROP 1 LASTPIN (-3125 1850) BN 11
J 2
(-3073 1858);
DISPLAY 0.489362 (-3073 1858);
PAINT MONO (-3073 1858);
FORCEPROP 2 LAST CDS_LIB standard
J 0
(-3075 1850);
DISPLAY INVISIBLE (-3075 1850);
FORCEPROP 2 LAST BOM_COST IO_SLOT
J 0
(-3575 1950);
DISPLAY 0.829787 (-3575 1950);
DISPLAY INVISIBLE (-3575 1950);
FORCEPROP 2 LAST ROOM RISER1
J 0
(-3575 1900);
DISPLAY 0.829787 (-3575 1900);
PAINT RED (-3575 1900);
DISPLAY INVISIBLE (-3575 1900);
FORCEPROP 1 LAST BODY_TYPE PLUMBING
J 2
(-3075 1800);
DISPLAY 0.702128 (-3075 1800);
PAINT GREEN (-3075 1800);
DISPLAY INVISIBLE (-3075 1800);
FORCEPROP 1 LAST HDL_TAP TRUE
J 2
(-3400 1725);
DISPLAY 0.702128 (-3400 1725);
PAINT GREEN (-3400 1725);
DISPLAY INVISIBLE (-3400 1725);
FORCEPROP 1 LAST PATH I310
J 2
(-3073 1850);
DISPLAY 0.872340 (-3073 1850);
PAINT GREEN (-3073 1850);
DISPLAY INVISIBLE (-3073 1850);
FORCEADD TAP..6
R 2
(-2925 1700);
FORCEPROP 3 LASTPIN (-2975 1700) SIG_NAME P5E_CPU0_G3_TX_DN<12>
J 0
(-2965 1710);
DISPLAY 0.659574 (-2965 1710);
PAINT MONO (-2965 1710);
DISPLAY INVISIBLE (-2965 1710);
FORCEPROP 1 LASTPIN (-2975 1700) BN 12
J 2
(-2923 1708);
DISPLAY 0.489362 (-2923 1708);
PAINT MONO (-2923 1708);
FORCEPROP 2 LAST CDS_LIB standard
J 0
(-2925 1700);
DISPLAY INVISIBLE (-2925 1700);
FORCEPROP 2 LAST BOM_COST IO_SLOT
J 0
(-3425 1800);
DISPLAY 0.829787 (-3425 1800);
DISPLAY INVISIBLE (-3425 1800);
FORCEPROP 2 LAST ROOM RISER1
J 0
(-3425 1750);
DISPLAY 0.829787 (-3425 1750);
PAINT RED (-3425 1750);
DISPLAY INVISIBLE (-3425 1750);
FORCEPROP 1 LAST BODY_TYPE PLUMBING
J 2
(-2925 1650);
DISPLAY 0.702128 (-2925 1650);
PAINT GREEN (-2925 1650);
DISPLAY INVISIBLE (-2925 1650);
FORCEPROP 1 LAST HDL_TAP TRUE
J 2
(-3250 1575);
DISPLAY 0.702128 (-3250 1575);
PAINT GREEN (-3250 1575);
DISPLAY INVISIBLE (-3250 1575);
FORCEPROP 1 LAST PATH I311
J 2
(-2923 1700);
DISPLAY 0.872340 (-2923 1700);
PAINT GREEN (-2923 1700);
DISPLAY INVISIBLE (-2923 1700);
FORCEADD TAP..6
R 2
(-2925 1600);
FORCEPROP 3 LASTPIN (-2975 1600) SIG_NAME P5E_CPU0_G3_TX_DN<13>
J 0
(-2965 1610);
DISPLAY 0.659574 (-2965 1610);
PAINT MONO (-2965 1610);
DISPLAY INVISIBLE (-2965 1610);
FORCEPROP 1 LASTPIN (-2975 1600) BN 13
J 2
(-2923 1608);
DISPLAY 0.489362 (-2923 1608);
PAINT MONO (-2923 1608);
FORCEPROP 2 LAST CDS_LIB standard
J 0
(-2925 1600);
DISPLAY INVISIBLE (-2925 1600);
FORCEPROP 2 LAST BOM_COST IO_SLOT
J 0
(-3425 1700);
DISPLAY 0.829787 (-3425 1700);
DISPLAY INVISIBLE (-3425 1700);
FORCEPROP 2 LAST ROOM RISER1
J 0
(-3425 1650);
DISPLAY 0.829787 (-3425 1650);
PAINT RED (-3425 1650);
DISPLAY INVISIBLE (-3425 1650);
FORCEPROP 1 LAST BODY_TYPE PLUMBING
J 2
(-2925 1550);
DISPLAY 0.702128 (-2925 1550);
PAINT GREEN (-2925 1550);
DISPLAY INVISIBLE (-2925 1550);
FORCEPROP 1 LAST HDL_TAP TRUE
J 2
(-3250 1475);
DISPLAY 0.702128 (-3250 1475);
PAINT GREEN (-3250 1475);
DISPLAY INVISIBLE (-3250 1475);
FORCEPROP 1 LAST PATH I312
J 2
(-2923 1600);
DISPLAY 0.872340 (-2923 1600);
PAINT GREEN (-2923 1600);
DISPLAY INVISIBLE (-2923 1600);
FORCEADD TAP..6
R 2
(-3075 1650);
FORCEPROP 3 LASTPIN (-3125 1650) SIG_NAME P5E_CPU0_G3_TX_DP<13>
J 0
(-3115 1660);
DISPLAY 0.659574 (-3115 1660);
PAINT MONO (-3115 1660);
DISPLAY INVISIBLE (-3115 1660);
FORCEPROP 1 LASTPIN (-3125 1650) BN 13
J 2
(-3073 1658);
DISPLAY 0.489362 (-3073 1658);
PAINT MONO (-3073 1658);
FORCEPROP 2 LAST CDS_LIB standard
J 0
(-3075 1650);
DISPLAY INVISIBLE (-3075 1650);
FORCEPROP 2 LAST BOM_COST IO_SLOT
J 0
(-3575 1750);
DISPLAY 0.829787 (-3575 1750);
DISPLAY INVISIBLE (-3575 1750);
FORCEPROP 2 LAST ROOM RISER1
J 0
(-3575 1700);
DISPLAY 0.829787 (-3575 1700);
PAINT RED (-3575 1700);
DISPLAY INVISIBLE (-3575 1700);
FORCEPROP 1 LAST BODY_TYPE PLUMBING
J 2
(-3075 1600);
DISPLAY 0.702128 (-3075 1600);
PAINT GREEN (-3075 1600);
DISPLAY INVISIBLE (-3075 1600);
FORCEPROP 1 LAST HDL_TAP TRUE
J 2
(-3400 1525);
DISPLAY 0.702128 (-3400 1525);
PAINT GREEN (-3400 1525);
DISPLAY INVISIBLE (-3400 1525);
FORCEPROP 1 LAST PATH I313
J 2
(-3073 1650);
DISPLAY 0.872340 (-3073 1650);
PAINT GREEN (-3073 1650);
DISPLAY INVISIBLE (-3073 1650);
FORCEADD TAP..6
R 2
(-3075 1750);
FORCEPROP 3 LASTPIN (-3125 1750) SIG_NAME P5E_CPU0_G3_TX_DP<12>
J 0
(-3115 1760);
DISPLAY 0.659574 (-3115 1760);
PAINT MONO (-3115 1760);
DISPLAY INVISIBLE (-3115 1760);
FORCEPROP 1 LASTPIN (-3125 1750) BN 12
J 2
(-3073 1758);
DISPLAY 0.489362 (-3073 1758);
PAINT MONO (-3073 1758);
FORCEPROP 2 LAST CDS_LIB standard
J 0
(-3075 1750);
DISPLAY INVISIBLE (-3075 1750);
FORCEPROP 2 LAST BOM_COST IO_SLOT
J 0
(-3575 1850);
DISPLAY 0.829787 (-3575 1850);
DISPLAY INVISIBLE (-3575 1850);
FORCEPROP 2 LAST ROOM RISER1
J 0
(-3575 1800);
DISPLAY 0.829787 (-3575 1800);
PAINT RED (-3575 1800);
DISPLAY INVISIBLE (-3575 1800);
FORCEPROP 1 LAST BODY_TYPE PLUMBING
J 2
(-3075 1700);
DISPLAY 0.702128 (-3075 1700);
PAINT GREEN (-3075 1700);
DISPLAY INVISIBLE (-3075 1700);
FORCEPROP 1 LAST HDL_TAP TRUE
J 2
(-3400 1625);
DISPLAY 0.702128 (-3400 1625);
PAINT GREEN (-3400 1625);
DISPLAY INVISIBLE (-3400 1625);
FORCEPROP 1 LAST PATH I314
J 2
(-3073 1750);
DISPLAY 0.872340 (-3073 1750);
PAINT GREEN (-3073 1750);
DISPLAY INVISIBLE (-3073 1750);
FORCEADD TAP..6
R 2
(-3075 1550);
FORCEPROP 3 LASTPIN (-3125 1550) SIG_NAME P5E_CPU0_G3_TX_DP<14>
J 0
(-3115 1560);
DISPLAY 0.659574 (-3115 1560);
PAINT MONO (-3115 1560);
DISPLAY INVISIBLE (-3115 1560);
FORCEPROP 1 LASTPIN (-3125 1550) BN 14
J 2
(-3073 1558);
DISPLAY 0.489362 (-3073 1558);
PAINT MONO (-3073 1558);
FORCEPROP 2 LAST CDS_LIB standard
J 0
(-3075 1550);
DISPLAY INVISIBLE (-3075 1550);
FORCEPROP 2 LAST BOM_COST IO_SLOT
J 0
(-3575 1650);
DISPLAY 0.829787 (-3575 1650);
DISPLAY INVISIBLE (-3575 1650);
FORCEPROP 2 LAST ROOM RISER1
J 0
(-3575 1600);
DISPLAY 0.829787 (-3575 1600);
PAINT RED (-3575 1600);
DISPLAY INVISIBLE (-3575 1600);
FORCEPROP 1 LAST BODY_TYPE PLUMBING
J 2
(-3075 1500);
DISPLAY 0.702128 (-3075 1500);
PAINT GREEN (-3075 1500);
DISPLAY INVISIBLE (-3075 1500);
FORCEPROP 1 LAST HDL_TAP TRUE
J 2
(-3400 1425);
DISPLAY 0.702128 (-3400 1425);
PAINT GREEN (-3400 1425);
DISPLAY INVISIBLE (-3400 1425);
FORCEPROP 1 LAST PATH I315
J 2
(-3073 1550);
DISPLAY 0.872340 (-3073 1550);
PAINT GREEN (-3073 1550);
DISPLAY INVISIBLE (-3073 1550);
FORCEADD TAP..6
R 2
(-2925 1500);
FORCEPROP 3 LASTPIN (-2975 1500) SIG_NAME P5E_CPU0_G3_TX_DN<14>
J 0
(-2965 1510);
DISPLAY 0.659574 (-2965 1510);
PAINT MONO (-2965 1510);
DISPLAY INVISIBLE (-2965 1510);
FORCEPROP 1 LASTPIN (-2975 1500) BN 14
J 2
(-2923 1508);
DISPLAY 0.489362 (-2923 1508);
PAINT MONO (-2923 1508);
FORCEPROP 2 LAST BOM_COST IO_SLOT
J 0
(-3425 1600);
DISPLAY 0.829787 (-3425 1600);
DISPLAY INVISIBLE (-3425 1600);
FORCEPROP 2 LAST CDS_LIB standard
J 0
(-2925 1500);
DISPLAY INVISIBLE (-2925 1500);
FORCEPROP 2 LAST ROOM RISER1
J 0
(-3425 1550);
DISPLAY 0.829787 (-3425 1550);
PAINT RED (-3425 1550);
DISPLAY INVISIBLE (-3425 1550);
FORCEPROP 1 LAST BODY_TYPE PLUMBING
J 2
(-2925 1450);
DISPLAY 0.702128 (-2925 1450);
PAINT GREEN (-2925 1450);
DISPLAY INVISIBLE (-2925 1450);
FORCEPROP 1 LAST HDL_TAP TRUE
J 2
(-3250 1375);
DISPLAY 0.702128 (-3250 1375);
PAINT GREEN (-3250 1375);
DISPLAY INVISIBLE (-3250 1375);
FORCEPROP 1 LAST PATH I316
J 2
(-2923 1500);
DISPLAY 0.872340 (-2923 1500);
PAINT GREEN (-2923 1500);
DISPLAY INVISIBLE (-2923 1500);
FORCEADD TAP..6
R 2
(-2925 1400);
FORCEPROP 3 LASTPIN (-2975 1400) SIG_NAME P5E_CPU0_G3_TX_DN<15>
J 0
(-2965 1410);
DISPLAY 0.659574 (-2965 1410);
PAINT MONO (-2965 1410);
DISPLAY INVISIBLE (-2965 1410);
FORCEPROP 1 LASTPIN (-2975 1400) BN 15
J 2
(-2923 1408);
DISPLAY 0.489362 (-2923 1408);
PAINT MONO (-2923 1408);
FORCEPROP 2 LAST CDS_LIB standard
J 0
(-2925 1400);
DISPLAY INVISIBLE (-2925 1400);
FORCEPROP 2 LAST BOM_COST IO_SLOT
J 0
(-3425 1500);
DISPLAY 0.829787 (-3425 1500);
DISPLAY INVISIBLE (-3425 1500);
FORCEPROP 2 LAST ROOM RISER1
J 0
(-3425 1450);
DISPLAY 0.829787 (-3425 1450);
PAINT RED (-3425 1450);
DISPLAY INVISIBLE (-3425 1450);
FORCEPROP 1 LAST BODY_TYPE PLUMBING
J 2
(-2925 1350);
DISPLAY 0.702128 (-2925 1350);
PAINT GREEN (-2925 1350);
DISPLAY INVISIBLE (-2925 1350);
FORCEPROP 1 LAST HDL_TAP TRUE
J 2
(-3250 1275);
DISPLAY 0.702128 (-3250 1275);
PAINT GREEN (-3250 1275);
DISPLAY INVISIBLE (-3250 1275);
FORCEPROP 1 LAST PATH I317
J 2
(-2923 1400);
DISPLAY 0.872340 (-2923 1400);
PAINT GREEN (-2923 1400);
DISPLAY INVISIBLE (-2923 1400);
FORCEADD TAP..6
R 2
(-3075 1450);
FORCEPROP 3 LASTPIN (-3125 1450) SIG_NAME P5E_CPU0_G3_TX_DP<15>
J 0
(-3115 1460);
DISPLAY 0.659574 (-3115 1460);
PAINT MONO (-3115 1460);
DISPLAY INVISIBLE (-3115 1460);
FORCEPROP 1 LASTPIN (-3125 1450) BN 15
J 2
(-3073 1458);
DISPLAY 0.489362 (-3073 1458);
PAINT MONO (-3073 1458);
FORCEPROP 2 LAST CDS_LIB standard
J 0
(-3075 1450);
DISPLAY INVISIBLE (-3075 1450);
FORCEPROP 2 LAST BOM_COST IO_SLOT
J 0
(-3575 1550);
DISPLAY 0.829787 (-3575 1550);
DISPLAY INVISIBLE (-3575 1550);
FORCEPROP 2 LAST ROOM RISER1
J 0
(-3575 1500);
DISPLAY 0.829787 (-3575 1500);
PAINT RED (-3575 1500);
DISPLAY INVISIBLE (-3575 1500);
FORCEPROP 1 LAST BODY_TYPE PLUMBING
J 2
(-3075 1400);
DISPLAY 0.702128 (-3075 1400);
PAINT GREEN (-3075 1400);
DISPLAY INVISIBLE (-3075 1400);
FORCEPROP 1 LAST HDL_TAP TRUE
J 2
(-3400 1325);
DISPLAY 0.702128 (-3400 1325);
PAINT GREEN (-3400 1325);
DISPLAY INVISIBLE (-3400 1325);
FORCEPROP 1 LAST PATH I318
J 2
(-3073 1450);
DISPLAY 0.872340 (-3073 1450);
PAINT GREEN (-3073 1450);
DISPLAY INVISIBLE (-3073 1450);
FORCEADD TAP..6
(-6500 2950);
FORCEPROP 3 LASTPIN (-6450 2950) SIG_NAME P5E_CPU0_G3_RX_DP<0>
J 0
(-6440 2960);
DISPLAY 0.659574 (-6440 2960);
PAINT MONO (-6440 2960);
DISPLAY INVISIBLE (-6440 2960);
FORCEPROP 1 LASTPIN (-6450 2950) BN 0
J 0
(-6502 2958);
DISPLAY 0.489362 (-6502 2958);
PAINT MONO (-6502 2958);
FORCEPROP 2 LAST CDS_LIB mstr_standard
J 0
(-6500 2950);
DISPLAY INVISIBLE (-6500 2950);
FORCEPROP 1 LAST BODY_TYPE PLUMBING
J 0
(-6500 2900);
DISPLAY 0.574468 (-6500 2900);
PAINT GREEN (-6500 2900);
DISPLAY INVISIBLE (-6500 2900);
FORCEPROP 1 LAST HDL_TAP TRUE
J 0
(-6175 2825);
DISPLAY 0.574468 (-6175 2825);
PAINT GREEN (-6175 2825);
DISPLAY INVISIBLE (-6175 2825);
FORCEPROP 1 LAST PATH I319
J 0
(-6502 2950);
DISPLAY 0.872340 (-6502 2950);
PAINT GREEN (-6502 2950);
DISPLAY INVISIBLE (-6502 2950);
FORCEADD TAP..6
(-6500 2850);
FORCEPROP 3 LASTPIN (-6450 2850) SIG_NAME P5E_CPU0_G3_RX_DP<1>
J 0
(-6440 2860);
DISPLAY 0.659574 (-6440 2860);
PAINT MONO (-6440 2860);
DISPLAY INVISIBLE (-6440 2860);
FORCEPROP 1 LASTPIN (-6450 2850) BN 1
J 0
(-6502 2858);
DISPLAY 0.489362 (-6502 2858);
PAINT MONO (-6502 2858);
FORCEPROP 2 LAST CDS_LIB mstr_standard
J 0
(-6500 2850);
DISPLAY INVISIBLE (-6500 2850);
FORCEPROP 1 LAST BODY_TYPE PLUMBING
J 0
(-6500 2800);
DISPLAY 0.574468 (-6500 2800);
PAINT GREEN (-6500 2800);
DISPLAY INVISIBLE (-6500 2800);
FORCEPROP 1 LAST HDL_TAP TRUE
J 0
(-6175 2725);
DISPLAY 0.574468 (-6175 2725);
PAINT GREEN (-6175 2725);
DISPLAY INVISIBLE (-6175 2725);
FORCEPROP 1 LAST PATH I320
J 0
(-6502 2850);
DISPLAY 0.872340 (-6502 2850);
PAINT GREEN (-6502 2850);
DISPLAY INVISIBLE (-6502 2850);
FORCEADD TAP..6
(-6650 2900);
FORCEPROP 3 LASTPIN (-6600 2900) SIG_NAME P5E_CPU0_G3_RX_DN<0>
J 0
(-6590 2910);
DISPLAY 0.659574 (-6590 2910);
PAINT MONO (-6590 2910);
DISPLAY INVISIBLE (-6590 2910);
FORCEPROP 1 LASTPIN (-6600 2900) BN 0
J 0
(-6652 2908);
DISPLAY 0.489362 (-6652 2908);
PAINT MONO (-6652 2908);
FORCEPROP 2 LAST CDS_LIB mstr_standard
J 0
(-6650 2900);
DISPLAY INVISIBLE (-6650 2900);
FORCEPROP 1 LAST BODY_TYPE PLUMBING
J 0
(-6650 2850);
DISPLAY 0.574468 (-6650 2850);
PAINT GREEN (-6650 2850);
DISPLAY INVISIBLE (-6650 2850);
FORCEPROP 1 LAST HDL_TAP TRUE
J 0
(-6325 2775);
DISPLAY 0.574468 (-6325 2775);
PAINT GREEN (-6325 2775);
DISPLAY INVISIBLE (-6325 2775);
FORCEPROP 1 LAST PATH I321
J 0
(-6652 2900);
DISPLAY 0.872340 (-6652 2900);
PAINT GREEN (-6652 2900);
DISPLAY INVISIBLE (-6652 2900);
FORCEADD TAP..6
(-6500 2750);
FORCEPROP 3 LASTPIN (-6450 2750) SIG_NAME P5E_CPU0_G3_RX_DP<2>
J 0
(-6440 2760);
DISPLAY 0.659574 (-6440 2760);
PAINT MONO (-6440 2760);
DISPLAY INVISIBLE (-6440 2760);
FORCEPROP 1 LASTPIN (-6450 2750) BN 2
J 0
(-6502 2758);
DISPLAY 0.489362 (-6502 2758);
PAINT MONO (-6502 2758);
FORCEPROP 2 LAST CDS_LIB mstr_standard
J 0
(-6500 2750);
DISPLAY INVISIBLE (-6500 2750);
FORCEPROP 1 LAST BODY_TYPE PLUMBING
J 0
(-6500 2700);
DISPLAY 0.574468 (-6500 2700);
PAINT GREEN (-6500 2700);
DISPLAY INVISIBLE (-6500 2700);
FORCEPROP 1 LAST HDL_TAP TRUE
J 0
(-6175 2625);
DISPLAY 0.574468 (-6175 2625);
PAINT GREEN (-6175 2625);
DISPLAY INVISIBLE (-6175 2625);
FORCEPROP 1 LAST PATH I322
J 0
(-6502 2750);
DISPLAY 0.872340 (-6502 2750);
PAINT GREEN (-6502 2750);
DISPLAY INVISIBLE (-6502 2750);
FORCEADD TAP..6
(-6500 2650);
FORCEPROP 3 LASTPIN (-6450 2650) SIG_NAME P5E_CPU0_G3_RX_DP<3>
J 0
(-6440 2660);
DISPLAY 0.659574 (-6440 2660);
PAINT MONO (-6440 2660);
DISPLAY INVISIBLE (-6440 2660);
FORCEPROP 1 LASTPIN (-6450 2650) BN 3
J 0
(-6502 2658);
DISPLAY 0.489362 (-6502 2658);
PAINT MONO (-6502 2658);
FORCEPROP 2 LAST CDS_LIB standard
J 0
(-6500 2650);
DISPLAY INVISIBLE (-6500 2650);
FORCEPROP 1 LAST BODY_TYPE PLUMBING
J 0
(-6500 2600);
DISPLAY 0.574468 (-6500 2600);
PAINT GREEN (-6500 2600);
DISPLAY INVISIBLE (-6500 2600);
FORCEPROP 1 LAST HDL_TAP TRUE
J 0
(-6175 2525);
DISPLAY 0.574468 (-6175 2525);
PAINT GREEN (-6175 2525);
DISPLAY INVISIBLE (-6175 2525);
FORCEPROP 1 LAST PATH I323
J 0
(-6502 2650);
DISPLAY 0.872340 (-6502 2650);
PAINT GREEN (-6502 2650);
DISPLAY INVISIBLE (-6502 2650);
FORCEADD TAP..6
(-6650 2800);
FORCEPROP 3 LASTPIN (-6600 2800) SIG_NAME P5E_CPU0_G3_RX_DN<1>
J 0
(-6590 2810);
DISPLAY 0.659574 (-6590 2810);
PAINT MONO (-6590 2810);
DISPLAY INVISIBLE (-6590 2810);
FORCEPROP 1 LASTPIN (-6600 2800) BN 1
J 0
(-6652 2808);
DISPLAY 0.489362 (-6652 2808);
PAINT MONO (-6652 2808);
FORCEPROP 2 LAST CDS_LIB mstr_standard
J 0
(-6650 2800);
DISPLAY INVISIBLE (-6650 2800);
FORCEPROP 1 LAST BODY_TYPE PLUMBING
J 0
(-6650 2750);
DISPLAY 0.574468 (-6650 2750);
PAINT GREEN (-6650 2750);
DISPLAY INVISIBLE (-6650 2750);
FORCEPROP 1 LAST HDL_TAP TRUE
J 0
(-6325 2675);
DISPLAY 0.574468 (-6325 2675);
PAINT GREEN (-6325 2675);
DISPLAY INVISIBLE (-6325 2675);
FORCEPROP 1 LAST PATH I324
J 0
(-6652 2800);
DISPLAY 0.872340 (-6652 2800);
PAINT GREEN (-6652 2800);
DISPLAY INVISIBLE (-6652 2800);
FORCEADD TAP..6
(-6650 2700);
FORCEPROP 3 LASTPIN (-6600 2700) SIG_NAME P5E_CPU0_G3_RX_DN<2>
J 0
(-6590 2710);
DISPLAY 0.659574 (-6590 2710);
PAINT MONO (-6590 2710);
DISPLAY INVISIBLE (-6590 2710);
FORCEPROP 1 LASTPIN (-6600 2700) BN 2
J 0
(-6652 2708);
DISPLAY 0.489362 (-6652 2708);
PAINT MONO (-6652 2708);
FORCEPROP 2 LAST CDS_LIB standard
J 0
(-6650 2700);
DISPLAY INVISIBLE (-6650 2700);
FORCEPROP 1 LAST BODY_TYPE PLUMBING
J 0
(-6650 2650);
DISPLAY 0.574468 (-6650 2650);
PAINT GREEN (-6650 2650);
DISPLAY INVISIBLE (-6650 2650);
FORCEPROP 1 LAST HDL_TAP TRUE
J 0
(-6325 2575);
DISPLAY 0.574468 (-6325 2575);
PAINT GREEN (-6325 2575);
DISPLAY INVISIBLE (-6325 2575);
FORCEPROP 1 LAST PATH I325
J 0
(-6652 2700);
DISPLAY 0.872340 (-6652 2700);
PAINT GREEN (-6652 2700);
DISPLAY INVISIBLE (-6652 2700);
FORCEADD TAP..6
(-6650 2600);
FORCEPROP 3 LASTPIN (-6600 2600) SIG_NAME P5E_CPU0_G3_RX_DN<3>
J 0
(-6590 2610);
DISPLAY 0.659574 (-6590 2610);
PAINT MONO (-6590 2610);
DISPLAY INVISIBLE (-6590 2610);
FORCEPROP 1 LASTPIN (-6600 2600) BN 3
J 0
(-6652 2608);
DISPLAY 0.489362 (-6652 2608);
PAINT MONO (-6652 2608);
FORCEPROP 2 LAST CDS_LIB standard
J 0
(-6650 2600);
DISPLAY INVISIBLE (-6650 2600);
FORCEPROP 1 LAST BODY_TYPE PLUMBING
J 0
(-6650 2550);
DISPLAY 0.574468 (-6650 2550);
PAINT GREEN (-6650 2550);
DISPLAY INVISIBLE (-6650 2550);
FORCEPROP 1 LAST HDL_TAP TRUE
J 0
(-6325 2475);
DISPLAY 0.574468 (-6325 2475);
PAINT GREEN (-6325 2475);
DISPLAY INVISIBLE (-6325 2475);
FORCEPROP 1 LAST PATH I326
J 0
(-6652 2600);
DISPLAY 0.872340 (-6652 2600);
PAINT GREEN (-6652 2600);
DISPLAY INVISIBLE (-6652 2600);
FORCEADD TAP..6
(-6500 2550);
FORCEPROP 3 LASTPIN (-6450 2550) SIG_NAME P5E_CPU0_G3_RX_DP<4>
J 0
(-6440 2560);
DISPLAY 0.659574 (-6440 2560);
PAINT MONO (-6440 2560);
DISPLAY INVISIBLE (-6440 2560);
FORCEPROP 1 LASTPIN (-6450 2550) BN 4
J 0
(-6502 2558);
DISPLAY 0.489362 (-6502 2558);
PAINT MONO (-6502 2558);
FORCEPROP 2 LAST CDS_LIB standard
J 0
(-6500 2550);
DISPLAY INVISIBLE (-6500 2550);
FORCEPROP 1 LAST BODY_TYPE PLUMBING
J 0
(-6500 2500);
DISPLAY 0.574468 (-6500 2500);
PAINT GREEN (-6500 2500);
DISPLAY INVISIBLE (-6500 2500);
FORCEPROP 1 LAST HDL_TAP TRUE
J 0
(-6175 2425);
DISPLAY 0.574468 (-6175 2425);
PAINT GREEN (-6175 2425);
DISPLAY INVISIBLE (-6175 2425);
FORCEPROP 1 LAST PATH I327
J 0
(-6502 2550);
DISPLAY 0.872340 (-6502 2550);
PAINT GREEN (-6502 2550);
DISPLAY INVISIBLE (-6502 2550);
FORCEADD TAP..6
(-6500 2450);
FORCEPROP 3 LASTPIN (-6450 2450) SIG_NAME P5E_CPU0_G3_RX_DP<5>
J 0
(-6440 2460);
DISPLAY 0.659574 (-6440 2460);
PAINT MONO (-6440 2460);
DISPLAY INVISIBLE (-6440 2460);
FORCEPROP 1 LASTPIN (-6450 2450) BN 5
J 0
(-6502 2458);
DISPLAY 0.489362 (-6502 2458);
PAINT MONO (-6502 2458);
FORCEPROP 2 LAST CDS_LIB standard
J 0
(-6500 2450);
DISPLAY INVISIBLE (-6500 2450);
FORCEPROP 1 LAST BODY_TYPE PLUMBING
J 0
(-6500 2400);
DISPLAY 0.574468 (-6500 2400);
PAINT GREEN (-6500 2400);
DISPLAY INVISIBLE (-6500 2400);
FORCEPROP 1 LAST HDL_TAP TRUE
J 0
(-6175 2325);
DISPLAY 0.574468 (-6175 2325);
PAINT GREEN (-6175 2325);
DISPLAY INVISIBLE (-6175 2325);
FORCEPROP 1 LAST PATH I328
J 0
(-6502 2450);
DISPLAY 0.872340 (-6502 2450);
PAINT GREEN (-6502 2450);
DISPLAY INVISIBLE (-6502 2450);
FORCEADD TAP..6
(-6500 2350);
FORCEPROP 3 LASTPIN (-6450 2350) SIG_NAME P5E_CPU0_G3_RX_DP<6>
J 0
(-6440 2360);
DISPLAY 0.659574 (-6440 2360);
PAINT MONO (-6440 2360);
DISPLAY INVISIBLE (-6440 2360);
FORCEPROP 1 LASTPIN (-6450 2350) BN 6
J 0
(-6502 2358);
DISPLAY 0.489362 (-6502 2358);
PAINT MONO (-6502 2358);
FORCEPROP 2 LAST CDS_LIB standard
J 0
(-6500 2350);
DISPLAY INVISIBLE (-6500 2350);
FORCEPROP 1 LAST BODY_TYPE PLUMBING
J 0
(-6500 2300);
DISPLAY 0.574468 (-6500 2300);
PAINT GREEN (-6500 2300);
DISPLAY INVISIBLE (-6500 2300);
FORCEPROP 1 LAST HDL_TAP TRUE
J 0
(-6175 2225);
DISPLAY 0.574468 (-6175 2225);
PAINT GREEN (-6175 2225);
DISPLAY INVISIBLE (-6175 2225);
FORCEPROP 1 LAST PATH I329
J 0
(-6502 2350);
DISPLAY 0.872340 (-6502 2350);
PAINT GREEN (-6502 2350);
DISPLAY INVISIBLE (-6502 2350);
FORCEADD TAP..6
(-6650 2500);
FORCEPROP 3 LASTPIN (-6600 2500) SIG_NAME P5E_CPU0_G3_RX_DN<4>
J 0
(-6590 2510);
DISPLAY 0.659574 (-6590 2510);
PAINT MONO (-6590 2510);
DISPLAY INVISIBLE (-6590 2510);
FORCEPROP 1 LASTPIN (-6600 2500) BN 4
J 0
(-6652 2508);
DISPLAY 0.489362 (-6652 2508);
PAINT MONO (-6652 2508);
FORCEPROP 2 LAST CDS_LIB standard
J 0
(-6650 2500);
DISPLAY INVISIBLE (-6650 2500);
FORCEPROP 1 LAST BODY_TYPE PLUMBING
J 0
(-6650 2450);
DISPLAY 0.574468 (-6650 2450);
PAINT GREEN (-6650 2450);
DISPLAY INVISIBLE (-6650 2450);
FORCEPROP 1 LAST HDL_TAP TRUE
J 0
(-6325 2375);
DISPLAY 0.574468 (-6325 2375);
PAINT GREEN (-6325 2375);
DISPLAY INVISIBLE (-6325 2375);
FORCEPROP 1 LAST PATH I330
J 0
(-6652 2500);
DISPLAY 0.872340 (-6652 2500);
PAINT GREEN (-6652 2500);
DISPLAY INVISIBLE (-6652 2500);
FORCEADD TAP..6
(-6650 2400);
FORCEPROP 3 LASTPIN (-6600 2400) SIG_NAME P5E_CPU0_G3_RX_DN<5>
J 0
(-6590 2410);
DISPLAY 0.659574 (-6590 2410);
PAINT MONO (-6590 2410);
DISPLAY INVISIBLE (-6590 2410);
FORCEPROP 1 LASTPIN (-6600 2400) BN 5
J 0
(-6652 2408);
DISPLAY 0.489362 (-6652 2408);
PAINT MONO (-6652 2408);
FORCEPROP 2 LAST CDS_LIB standard
J 0
(-6650 2400);
DISPLAY INVISIBLE (-6650 2400);
FORCEPROP 1 LAST BODY_TYPE PLUMBING
J 0
(-6650 2350);
DISPLAY 0.574468 (-6650 2350);
PAINT GREEN (-6650 2350);
DISPLAY INVISIBLE (-6650 2350);
FORCEPROP 1 LAST HDL_TAP TRUE
J 0
(-6325 2275);
DISPLAY 0.574468 (-6325 2275);
PAINT GREEN (-6325 2275);
DISPLAY INVISIBLE (-6325 2275);
FORCEPROP 1 LAST PATH I331
J 0
(-6652 2400);
DISPLAY 0.872340 (-6652 2400);
PAINT GREEN (-6652 2400);
DISPLAY INVISIBLE (-6652 2400);
FORCEADD TAP..6
(-6500 2250);
FORCEPROP 3 LASTPIN (-6450 2250) SIG_NAME P5E_CPU0_G3_RX_DP<7>
J 0
(-6440 2260);
DISPLAY 0.659574 (-6440 2260);
PAINT MONO (-6440 2260);
DISPLAY INVISIBLE (-6440 2260);
FORCEPROP 1 LASTPIN (-6450 2250) BN 7
J 0
(-6502 2258);
DISPLAY 0.489362 (-6502 2258);
PAINT MONO (-6502 2258);
FORCEPROP 2 LAST CDS_LIB standard
J 0
(-6500 2250);
DISPLAY INVISIBLE (-6500 2250);
FORCEPROP 1 LAST BODY_TYPE PLUMBING
J 0
(-6500 2200);
DISPLAY 0.574468 (-6500 2200);
PAINT GREEN (-6500 2200);
DISPLAY INVISIBLE (-6500 2200);
FORCEPROP 1 LAST HDL_TAP TRUE
J 0
(-6175 2125);
DISPLAY 0.574468 (-6175 2125);
PAINT GREEN (-6175 2125);
DISPLAY INVISIBLE (-6175 2125);
FORCEPROP 1 LAST PATH I332
J 0
(-6502 2250);
DISPLAY 0.872340 (-6502 2250);
PAINT GREEN (-6502 2250);
DISPLAY INVISIBLE (-6502 2250);
FORCEADD TAP..6
(-6500 2150);
FORCEPROP 3 LASTPIN (-6450 2150) SIG_NAME P5E_CPU0_G3_RX_DP<8>
J 0
(-6440 2160);
DISPLAY 0.659574 (-6440 2160);
PAINT MONO (-6440 2160);
DISPLAY INVISIBLE (-6440 2160);
FORCEPROP 1 LASTPIN (-6450 2150) BN 8
J 0
(-6502 2158);
DISPLAY 0.489362 (-6502 2158);
PAINT MONO (-6502 2158);
FORCEPROP 2 LAST CDS_LIB standard
J 0
(-6500 2150);
DISPLAY INVISIBLE (-6500 2150);
FORCEPROP 1 LAST BODY_TYPE PLUMBING
J 0
(-6500 2100);
DISPLAY 0.574468 (-6500 2100);
PAINT GREEN (-6500 2100);
DISPLAY INVISIBLE (-6500 2100);
FORCEPROP 1 LAST HDL_TAP TRUE
J 0
(-6175 2025);
DISPLAY 0.574468 (-6175 2025);
PAINT GREEN (-6175 2025);
DISPLAY INVISIBLE (-6175 2025);
FORCEPROP 1 LAST PATH I333
J 0
(-6502 2150);
DISPLAY 0.872340 (-6502 2150);
PAINT GREEN (-6502 2150);
DISPLAY INVISIBLE (-6502 2150);
FORCEADD TAP..6
(-6500 2050);
FORCEPROP 3 LASTPIN (-6450 2050) SIG_NAME P5E_CPU0_G3_RX_DP<9>
J 0
(-6440 2060);
DISPLAY 0.659574 (-6440 2060);
PAINT MONO (-6440 2060);
DISPLAY INVISIBLE (-6440 2060);
FORCEPROP 1 LASTPIN (-6450 2050) BN 9
J 0
(-6502 2058);
DISPLAY 0.489362 (-6502 2058);
PAINT MONO (-6502 2058);
FORCEPROP 2 LAST CDS_LIB standard
J 0
(-6500 2050);
DISPLAY INVISIBLE (-6500 2050);
FORCEPROP 1 LAST BODY_TYPE PLUMBING
J 0
(-6500 2000);
DISPLAY 0.574468 (-6500 2000);
PAINT GREEN (-6500 2000);
DISPLAY INVISIBLE (-6500 2000);
FORCEPROP 1 LAST HDL_TAP TRUE
J 0
(-6175 1925);
DISPLAY 0.574468 (-6175 1925);
PAINT GREEN (-6175 1925);
DISPLAY INVISIBLE (-6175 1925);
FORCEPROP 1 LAST PATH I334
J 0
(-6502 2050);
DISPLAY 0.872340 (-6502 2050);
PAINT GREEN (-6502 2050);
DISPLAY INVISIBLE (-6502 2050);
FORCEADD TAP..6
(-6650 2300);
FORCEPROP 3 LASTPIN (-6600 2300) SIG_NAME P5E_CPU0_G3_RX_DN<6>
J 0
(-6590 2310);
DISPLAY 0.659574 (-6590 2310);
PAINT MONO (-6590 2310);
DISPLAY INVISIBLE (-6590 2310);
FORCEPROP 1 LASTPIN (-6600 2300) BN 6
J 0
(-6652 2308);
DISPLAY 0.489362 (-6652 2308);
PAINT MONO (-6652 2308);
FORCEPROP 2 LAST CDS_LIB standard
J 0
(-6650 2300);
DISPLAY INVISIBLE (-6650 2300);
FORCEPROP 1 LAST BODY_TYPE PLUMBING
J 0
(-6650 2250);
DISPLAY 0.574468 (-6650 2250);
PAINT GREEN (-6650 2250);
DISPLAY INVISIBLE (-6650 2250);
FORCEPROP 1 LAST HDL_TAP TRUE
J 0
(-6325 2175);
DISPLAY 0.574468 (-6325 2175);
PAINT GREEN (-6325 2175);
DISPLAY INVISIBLE (-6325 2175);
FORCEPROP 1 LAST PATH I335
J 0
(-6652 2300);
DISPLAY 0.872340 (-6652 2300);
PAINT GREEN (-6652 2300);
DISPLAY INVISIBLE (-6652 2300);
FORCEADD TAP..6
(-6650 2200);
FORCEPROP 3 LASTPIN (-6600 2200) SIG_NAME P5E_CPU0_G3_RX_DN<7>
J 0
(-6590 2210);
DISPLAY 0.659574 (-6590 2210);
PAINT MONO (-6590 2210);
DISPLAY INVISIBLE (-6590 2210);
FORCEPROP 1 LASTPIN (-6600 2200) BN 7
J 0
(-6652 2208);
DISPLAY 0.489362 (-6652 2208);
PAINT MONO (-6652 2208);
FORCEPROP 2 LAST CDS_LIB standard
J 0
(-6650 2200);
DISPLAY INVISIBLE (-6650 2200);
FORCEPROP 1 LAST BODY_TYPE PLUMBING
J 0
(-6650 2150);
DISPLAY 0.574468 (-6650 2150);
PAINT GREEN (-6650 2150);
DISPLAY INVISIBLE (-6650 2150);
FORCEPROP 1 LAST HDL_TAP TRUE
J 0
(-6325 2075);
DISPLAY 0.574468 (-6325 2075);
PAINT GREEN (-6325 2075);
DISPLAY INVISIBLE (-6325 2075);
FORCEPROP 1 LAST PATH I336
J 0
(-6652 2200);
DISPLAY 0.872340 (-6652 2200);
PAINT GREEN (-6652 2200);
DISPLAY INVISIBLE (-6652 2200);
FORCEADD TAP..6
(-6650 2100);
FORCEPROP 3 LASTPIN (-6600 2100) SIG_NAME P5E_CPU0_G3_RX_DN<8>
J 0
(-6590 2110);
DISPLAY 0.659574 (-6590 2110);
PAINT MONO (-6590 2110);
DISPLAY INVISIBLE (-6590 2110);
FORCEPROP 1 LASTPIN (-6600 2100) BN 8
J 0
(-6652 2108);
DISPLAY 0.489362 (-6652 2108);
PAINT MONO (-6652 2108);
FORCEPROP 2 LAST CDS_LIB standard
J 0
(-6650 2100);
DISPLAY INVISIBLE (-6650 2100);
FORCEPROP 1 LAST BODY_TYPE PLUMBING
J 0
(-6650 2050);
DISPLAY 0.574468 (-6650 2050);
PAINT GREEN (-6650 2050);
DISPLAY INVISIBLE (-6650 2050);
FORCEPROP 1 LAST HDL_TAP TRUE
J 0
(-6325 1975);
DISPLAY 0.574468 (-6325 1975);
PAINT GREEN (-6325 1975);
DISPLAY INVISIBLE (-6325 1975);
FORCEPROP 1 LAST PATH I337
J 0
(-6652 2100);
DISPLAY 0.872340 (-6652 2100);
PAINT GREEN (-6652 2100);
DISPLAY INVISIBLE (-6652 2100);
FORCEADD OFFPAGE..1
(-7700 3175);
FORCEPROP 2 LASTPIN (-7650 3175) SIG_NAME P5E_CPU0_G3_RX_DP<15:0>
J 0
(-7635 3185);
DISPLAY 0.489362 (-7635 3185);
FORCEPROP 2 LAST $XR0 131 
J 0
(-7982 3175);
DISPLAY 0.638298 (-7982 3175);
PAINT MONO (-7982 3175);
FORCEPROP 2 LAST CDS_LIB standard
J 0
(-7700 3175);
DISPLAY INVISIBLE (-7700 3175);
FORCEPROP 1 LAST OFFPAGE TRUE
J 0
(-7375 3050);
DISPLAY 0.872340 (-7375 3050);
PAINT GREEN (-7375 3050);
DISPLAY INVISIBLE (-7375 3050);
FORCEPROP 1 LAST COMMENT_BODY TRUE
J 0
(-7575 3075);
DISPLAY 0.872340 (-7575 3075);
PAINT GREEN (-7575 3075);
DISPLAY INVISIBLE (-7575 3075);
FORCEPROP 2 LAST PATH I338
J 0
(-7900 3225);
DISPLAY 1.021277 (-7900 3225);
DISPLAY INVISIBLE (-7900 3225);
FORCEADD OFFPAGE..1
(-7700 3125);
FORCEPROP 2 LASTPIN (-7650 3125) SIG_NAME P5E_CPU0_G3_RX_DN<15:0>
J 0
(-7635 3135);
DISPLAY 0.489362 (-7635 3135);
FORCEPROP 2 LAST $XR0 131 
J 0
(-7982 3125);
DISPLAY 0.638298 (-7982 3125);
PAINT MONO (-7982 3125);
FORCEPROP 2 LAST CDS_LIB standard
J 0
(-7700 3125);
DISPLAY INVISIBLE (-7700 3125);
FORCEPROP 1 LAST OFFPAGE TRUE
J 0
(-7375 3000);
DISPLAY 0.872340 (-7375 3000);
PAINT GREEN (-7375 3000);
DISPLAY INVISIBLE (-7375 3000);
FORCEPROP 1 LAST COMMENT_BODY TRUE
J 0
(-7575 3025);
DISPLAY 0.872340 (-7575 3025);
PAINT GREEN (-7575 3025);
DISPLAY INVISIBLE (-7575 3025);
FORCEPROP 2 LAST PATH I339
J 0
(-7900 3175);
DISPLAY 1.021277 (-7900 3175);
DISPLAY INVISIBLE (-7900 3175);
FORCEADD TAP..6
(-6500 1950);
FORCEPROP 3 LASTPIN (-6450 1950) SIG_NAME P5E_CPU0_G3_RX_DP<10>
J 0
(-6440 1960);
DISPLAY 0.659574 (-6440 1960);
PAINT MONO (-6440 1960);
DISPLAY INVISIBLE (-6440 1960);
FORCEPROP 1 LASTPIN (-6450 1950) BN 10
J 0
(-6502 1958);
DISPLAY 0.489362 (-6502 1958);
PAINT MONO (-6502 1958);
FORCEPROP 2 LAST CDS_LIB standard
J 0
(-6500 1950);
DISPLAY INVISIBLE (-6500 1950);
FORCEPROP 1 LAST BODY_TYPE PLUMBING
J 0
(-6500 1900);
DISPLAY 0.574468 (-6500 1900);
PAINT GREEN (-6500 1900);
DISPLAY INVISIBLE (-6500 1900);
FORCEPROP 1 LAST HDL_TAP TRUE
J 0
(-6175 1825);
DISPLAY 0.574468 (-6175 1825);
PAINT GREEN (-6175 1825);
DISPLAY INVISIBLE (-6175 1825);
FORCEPROP 1 LAST PATH I340
J 0
(-6502 1950);
DISPLAY 0.872340 (-6502 1950);
PAINT GREEN (-6502 1950);
DISPLAY INVISIBLE (-6502 1950);
FORCEADD TAP..6
(-6500 1850);
FORCEPROP 3 LASTPIN (-6450 1850) SIG_NAME P5E_CPU0_G3_RX_DP<11>
J 0
(-6440 1860);
DISPLAY 0.659574 (-6440 1860);
PAINT MONO (-6440 1860);
DISPLAY INVISIBLE (-6440 1860);
FORCEPROP 1 LASTPIN (-6450 1850) BN 11
J 0
(-6502 1858);
DISPLAY 0.489362 (-6502 1858);
PAINT MONO (-6502 1858);
FORCEPROP 2 LAST CDS_LIB standard
J 0
(-6500 1850);
DISPLAY INVISIBLE (-6500 1850);
FORCEPROP 1 LAST BODY_TYPE PLUMBING
J 0
(-6500 1800);
DISPLAY 0.574468 (-6500 1800);
PAINT GREEN (-6500 1800);
DISPLAY INVISIBLE (-6500 1800);
FORCEPROP 1 LAST HDL_TAP TRUE
J 0
(-6175 1725);
DISPLAY 0.574468 (-6175 1725);
PAINT GREEN (-6175 1725);
DISPLAY INVISIBLE (-6175 1725);
FORCEPROP 1 LAST PATH I341
J 0
(-6502 1850);
DISPLAY 0.872340 (-6502 1850);
PAINT GREEN (-6502 1850);
DISPLAY INVISIBLE (-6502 1850);
FORCEADD TAP..6
(-6650 2000);
FORCEPROP 3 LASTPIN (-6600 2000) SIG_NAME P5E_CPU0_G3_RX_DN<9>
J 0
(-6590 2010);
DISPLAY 0.659574 (-6590 2010);
PAINT MONO (-6590 2010);
DISPLAY INVISIBLE (-6590 2010);
FORCEPROP 1 LASTPIN (-6600 2000) BN 9
J 0
(-6652 2008);
DISPLAY 0.489362 (-6652 2008);
PAINT MONO (-6652 2008);
FORCEPROP 2 LAST CDS_LIB standard
J 0
(-6650 2000);
DISPLAY INVISIBLE (-6650 2000);
FORCEPROP 1 LAST BODY_TYPE PLUMBING
J 0
(-6650 1950);
DISPLAY 0.574468 (-6650 1950);
PAINT GREEN (-6650 1950);
DISPLAY INVISIBLE (-6650 1950);
FORCEPROP 1 LAST HDL_TAP TRUE
J 0
(-6325 1875);
DISPLAY 0.574468 (-6325 1875);
PAINT GREEN (-6325 1875);
DISPLAY INVISIBLE (-6325 1875);
FORCEPROP 1 LAST PATH I342
J 0
(-6652 2000);
DISPLAY 0.872340 (-6652 2000);
PAINT GREEN (-6652 2000);
DISPLAY INVISIBLE (-6652 2000);
FORCEADD TAP..6
(-6650 1900);
FORCEPROP 3 LASTPIN (-6600 1900) SIG_NAME P5E_CPU0_G3_RX_DN<10>
J 0
(-6590 1910);
DISPLAY 0.659574 (-6590 1910);
PAINT MONO (-6590 1910);
DISPLAY INVISIBLE (-6590 1910);
FORCEPROP 1 LASTPIN (-6600 1900) BN 10
J 0
(-6652 1908);
DISPLAY 0.489362 (-6652 1908);
PAINT MONO (-6652 1908);
FORCEPROP 2 LAST CDS_LIB standard
J 0
(-6650 1900);
DISPLAY INVISIBLE (-6650 1900);
FORCEPROP 1 LAST BODY_TYPE PLUMBING
J 0
(-6650 1850);
DISPLAY 0.574468 (-6650 1850);
PAINT GREEN (-6650 1850);
DISPLAY INVISIBLE (-6650 1850);
FORCEPROP 1 LAST HDL_TAP TRUE
J 0
(-6325 1775);
DISPLAY 0.574468 (-6325 1775);
PAINT GREEN (-6325 1775);
DISPLAY INVISIBLE (-6325 1775);
FORCEPROP 1 LAST PATH I343
J 0
(-6652 1900);
DISPLAY 0.872340 (-6652 1900);
PAINT GREEN (-6652 1900);
DISPLAY INVISIBLE (-6652 1900);
FORCEADD TAP..6
(-6650 1800);
FORCEPROP 3 LASTPIN (-6600 1800) SIG_NAME P5E_CPU0_G3_RX_DN<11>
J 0
(-6590 1810);
DISPLAY 0.659574 (-6590 1810);
PAINT MONO (-6590 1810);
DISPLAY INVISIBLE (-6590 1810);
FORCEPROP 1 LASTPIN (-6600 1800) BN 11
J 0
(-6652 1808);
DISPLAY 0.489362 (-6652 1808);
PAINT MONO (-6652 1808);
FORCEPROP 2 LAST CDS_LIB standard
J 0
(-6650 1800);
DISPLAY INVISIBLE (-6650 1800);
FORCEPROP 1 LAST BODY_TYPE PLUMBING
J 0
(-6650 1750);
DISPLAY 0.574468 (-6650 1750);
PAINT GREEN (-6650 1750);
DISPLAY INVISIBLE (-6650 1750);
FORCEPROP 1 LAST HDL_TAP TRUE
J 0
(-6325 1675);
DISPLAY 0.574468 (-6325 1675);
PAINT GREEN (-6325 1675);
DISPLAY INVISIBLE (-6325 1675);
FORCEPROP 1 LAST PATH I344
J 0
(-6652 1800);
DISPLAY 0.872340 (-6652 1800);
PAINT GREEN (-6652 1800);
DISPLAY INVISIBLE (-6652 1800);
FORCEADD TAP..6
(-6500 1650);
FORCEPROP 3 LASTPIN (-6450 1650) SIG_NAME P5E_CPU0_G3_RX_DP<13>
J 0
(-6440 1660);
DISPLAY 0.659574 (-6440 1660);
PAINT MONO (-6440 1660);
DISPLAY INVISIBLE (-6440 1660);
FORCEPROP 1 LASTPIN (-6450 1650) BN 13
J 0
(-6502 1658);
DISPLAY 0.489362 (-6502 1658);
PAINT MONO (-6502 1658);
FORCEPROP 2 LAST CDS_LIB standard
J 0
(-6500 1650);
DISPLAY INVISIBLE (-6500 1650);
FORCEPROP 1 LAST BODY_TYPE PLUMBING
J 0
(-6500 1600);
DISPLAY 0.574468 (-6500 1600);
PAINT GREEN (-6500 1600);
DISPLAY INVISIBLE (-6500 1600);
FORCEPROP 1 LAST HDL_TAP TRUE
J 0
(-6175 1525);
DISPLAY 0.574468 (-6175 1525);
PAINT GREEN (-6175 1525);
DISPLAY INVISIBLE (-6175 1525);
FORCEPROP 1 LAST PATH I345
J 0
(-6502 1650);
DISPLAY 0.872340 (-6502 1650);
PAINT GREEN (-6502 1650);
DISPLAY INVISIBLE (-6502 1650);
FORCEADD TAP..6
(-6500 1750);
FORCEPROP 3 LASTPIN (-6450 1750) SIG_NAME P5E_CPU0_G3_RX_DP<12>
J 0
(-6440 1760);
DISPLAY 0.659574 (-6440 1760);
PAINT MONO (-6440 1760);
DISPLAY INVISIBLE (-6440 1760);
FORCEPROP 1 LASTPIN (-6450 1750) BN 12
J 0
(-6502 1758);
DISPLAY 0.489362 (-6502 1758);
PAINT MONO (-6502 1758);
FORCEPROP 2 LAST CDS_LIB standard
J 0
(-6500 1750);
DISPLAY INVISIBLE (-6500 1750);
FORCEPROP 1 LAST BODY_TYPE PLUMBING
J 0
(-6500 1700);
DISPLAY 0.574468 (-6500 1700);
PAINT GREEN (-6500 1700);
DISPLAY INVISIBLE (-6500 1700);
FORCEPROP 1 LAST HDL_TAP TRUE
J 0
(-6175 1625);
DISPLAY 0.574468 (-6175 1625);
PAINT GREEN (-6175 1625);
DISPLAY INVISIBLE (-6175 1625);
FORCEPROP 1 LAST PATH I346
J 0
(-6502 1750);
DISPLAY 0.872340 (-6502 1750);
PAINT GREEN (-6502 1750);
DISPLAY INVISIBLE (-6502 1750);
FORCEADD TAP..6
(-6500 1550);
FORCEPROP 3 LASTPIN (-6450 1550) SIG_NAME P5E_CPU0_G3_RX_DP<14>
J 0
(-6440 1560);
DISPLAY 0.659574 (-6440 1560);
PAINT MONO (-6440 1560);
DISPLAY INVISIBLE (-6440 1560);
FORCEPROP 1 LASTPIN (-6450 1550) BN 14
J 0
(-6502 1558);
DISPLAY 0.489362 (-6502 1558);
PAINT MONO (-6502 1558);
FORCEPROP 2 LAST CDS_LIB standard
J 0
(-6500 1550);
DISPLAY INVISIBLE (-6500 1550);
FORCEPROP 1 LAST BODY_TYPE PLUMBING
J 0
(-6500 1500);
DISPLAY 0.574468 (-6500 1500);
PAINT GREEN (-6500 1500);
DISPLAY INVISIBLE (-6500 1500);
FORCEPROP 1 LAST HDL_TAP TRUE
J 0
(-6175 1425);
DISPLAY 0.574468 (-6175 1425);
PAINT GREEN (-6175 1425);
DISPLAY INVISIBLE (-6175 1425);
FORCEPROP 1 LAST PATH I347
J 0
(-6502 1550);
DISPLAY 0.872340 (-6502 1550);
PAINT GREEN (-6502 1550);
DISPLAY INVISIBLE (-6502 1550);
FORCEADD TAP..6
(-6650 1700);
FORCEPROP 3 LASTPIN (-6600 1700) SIG_NAME P5E_CPU0_G3_RX_DN<12>
J 0
(-6590 1710);
DISPLAY 0.659574 (-6590 1710);
PAINT MONO (-6590 1710);
DISPLAY INVISIBLE (-6590 1710);
FORCEPROP 1 LASTPIN (-6600 1700) BN 12
J 0
(-6652 1708);
DISPLAY 0.489362 (-6652 1708);
PAINT MONO (-6652 1708);
FORCEPROP 2 LAST CDS_LIB standard
J 0
(-6650 1700);
DISPLAY INVISIBLE (-6650 1700);
FORCEPROP 1 LAST BODY_TYPE PLUMBING
J 0
(-6650 1650);
DISPLAY 0.574468 (-6650 1650);
PAINT GREEN (-6650 1650);
DISPLAY INVISIBLE (-6650 1650);
FORCEPROP 1 LAST HDL_TAP TRUE
J 0
(-6325 1575);
DISPLAY 0.574468 (-6325 1575);
PAINT GREEN (-6325 1575);
DISPLAY INVISIBLE (-6325 1575);
FORCEPROP 1 LAST PATH I348
J 0
(-6652 1700);
DISPLAY 0.872340 (-6652 1700);
PAINT GREEN (-6652 1700);
DISPLAY INVISIBLE (-6652 1700);
FORCEADD TAP..6
(-6650 1600);
FORCEPROP 3 LASTPIN (-6600 1600) SIG_NAME P5E_CPU0_G3_RX_DN<13>
J 0
(-6590 1610);
DISPLAY 0.659574 (-6590 1610);
PAINT MONO (-6590 1610);
DISPLAY INVISIBLE (-6590 1610);
FORCEPROP 1 LASTPIN (-6600 1600) BN 13
J 0
(-6652 1608);
DISPLAY 0.489362 (-6652 1608);
PAINT MONO (-6652 1608);
FORCEPROP 2 LAST CDS_LIB standard
J 0
(-6650 1600);
DISPLAY INVISIBLE (-6650 1600);
FORCEPROP 1 LAST BODY_TYPE PLUMBING
J 0
(-6650 1550);
DISPLAY 0.574468 (-6650 1550);
PAINT GREEN (-6650 1550);
DISPLAY INVISIBLE (-6650 1550);
FORCEPROP 1 LAST HDL_TAP TRUE
J 0
(-6325 1475);
DISPLAY 0.574468 (-6325 1475);
PAINT GREEN (-6325 1475);
DISPLAY INVISIBLE (-6325 1475);
FORCEPROP 1 LAST PATH I349
J 0
(-6652 1600);
DISPLAY 0.872340 (-6652 1600);
PAINT GREEN (-6652 1600);
DISPLAY INVISIBLE (-6652 1600);
FORCEADD TAP..6
(-6500 1450);
FORCEPROP 3 LASTPIN (-6450 1450) SIG_NAME P5E_CPU0_G3_RX_DP<15>
J 0
(-6440 1460);
DISPLAY 0.659574 (-6440 1460);
PAINT MONO (-6440 1460);
DISPLAY INVISIBLE (-6440 1460);
FORCEPROP 1 LASTPIN (-6450 1450) BN 15
J 0
(-6502 1458);
DISPLAY 0.489362 (-6502 1458);
PAINT MONO (-6502 1458);
FORCEPROP 2 LAST CDS_LIB standard
J 0
(-6500 1450);
DISPLAY INVISIBLE (-6500 1450);
FORCEPROP 1 LAST BODY_TYPE PLUMBING
J 0
(-6500 1400);
DISPLAY 0.574468 (-6500 1400);
PAINT GREEN (-6500 1400);
DISPLAY INVISIBLE (-6500 1400);
FORCEPROP 1 LAST HDL_TAP TRUE
J 0
(-6175 1325);
DISPLAY 0.574468 (-6175 1325);
PAINT GREEN (-6175 1325);
DISPLAY INVISIBLE (-6175 1325);
FORCEPROP 1 LAST PATH I350
J 0
(-6502 1450);
DISPLAY 0.872340 (-6502 1450);
PAINT GREEN (-6502 1450);
DISPLAY INVISIBLE (-6502 1450);
FORCEADD TAP..6
(-6650 1500);
FORCEPROP 3 LASTPIN (-6600 1500) SIG_NAME P5E_CPU0_G3_RX_DN<14>
J 0
(-6590 1510);
DISPLAY 0.659574 (-6590 1510);
PAINT MONO (-6590 1510);
DISPLAY INVISIBLE (-6590 1510);
FORCEPROP 1 LASTPIN (-6600 1500) BN 14
J 0
(-6652 1508);
DISPLAY 0.489362 (-6652 1508);
PAINT MONO (-6652 1508);
FORCEPROP 2 LAST CDS_LIB standard
J 0
(-6650 1500);
DISPLAY INVISIBLE (-6650 1500);
FORCEPROP 1 LAST BODY_TYPE PLUMBING
J 0
(-6650 1450);
DISPLAY 0.574468 (-6650 1450);
PAINT GREEN (-6650 1450);
DISPLAY INVISIBLE (-6650 1450);
FORCEPROP 1 LAST HDL_TAP TRUE
J 0
(-6325 1375);
DISPLAY 0.574468 (-6325 1375);
PAINT GREEN (-6325 1375);
DISPLAY INVISIBLE (-6325 1375);
FORCEPROP 1 LAST PATH I351
J 0
(-6652 1500);
DISPLAY 0.872340 (-6652 1500);
PAINT GREEN (-6652 1500);
DISPLAY INVISIBLE (-6652 1500);
FORCEADD TAP..6
(-6650 1400);
FORCEPROP 3 LASTPIN (-6600 1400) SIG_NAME P5E_CPU0_G3_RX_DN<15>
J 0
(-6590 1410);
DISPLAY 0.659574 (-6590 1410);
PAINT MONO (-6590 1410);
DISPLAY INVISIBLE (-6590 1410);
FORCEPROP 1 LASTPIN (-6600 1400) BN 15
J 0
(-6652 1408);
DISPLAY 0.489362 (-6652 1408);
PAINT MONO (-6652 1408);
FORCEPROP 2 LAST CDS_LIB standard
J 0
(-6650 1400);
DISPLAY INVISIBLE (-6650 1400);
FORCEPROP 1 LAST BODY_TYPE PLUMBING
J 0
(-6650 1350);
DISPLAY 0.574468 (-6650 1350);
PAINT GREEN (-6650 1350);
DISPLAY INVISIBLE (-6650 1350);
FORCEPROP 1 LAST HDL_TAP TRUE
J 0
(-6325 1275);
DISPLAY 0.574468 (-6325 1275);
PAINT GREEN (-6325 1275);
DISPLAY INVISIBLE (-6325 1275);
FORCEPROP 1 LAST PATH I352
J 0
(-6652 1400);
DISPLAY 0.872340 (-6652 1400);
PAINT GREEN (-6652 1400);
DISPLAY INVISIBLE (-6652 1400);
FORCEADD QUANTA_TITLE_BLOCK_C..1
(-100 100);
FORCEPROP 0 LAST CDS_CON_LAST_MODIFIED Thu Sep 14 16:11:51 2023
J 0
(-1985 115);
DISPLAY INVISIBLE (-1985 115);
FORCEPROP 1 LAST CUSTOM_TXT_CDS <CON_LAST_MODIFIED>
J 0
(-1985 115);
DISPLAY 0.978723 (-1985 115);
FORCEPROP 2 LAST CUSTOM_TXT_CDS <XR_PAGE_TITLE>
J 0
(-7990 5350);
DISPLAY 0.638298 (-7990 5350);
PAINT PINK (-7990 5350);
DISPLAY INVISIBLE (-7990 5350);
FORCEPROP 1 LAST CUSTOM_TXT_CDS <NAME_2>
J 0
(-3275 150);
FORCEPROP 1 LAST CUSTOM_TXT_CDS <NAME_1>
J 0
(-3275 275);
FORCEPROP 1 LAST CUSTOM_TXT_CDS <Q_NUMBER>
J 0
(-1503 203);
DISPLAY 1.212766 (-1503 203);
FORCEPROP 1 LAST CUSTOM_TXT_CDS <Q_PROJ>
J 0
(-2482 202);
DISPLAY 1.212766 (-2482 202);
FORCEPROP 1 LAST CUSTOM_TXT_CDS <Q_REV>
J 0
(-284 203);
DISPLAY 1.212766 (-284 203);
FORCEPROP 1 LAST CUSTOM_TXT_CDS <CON_PAGE_NUM> OF <CON_TOTAL_PAGES>
J 0
(-546 118);
DISPLAY 0.978723 (-546 118);
FORCEPROP 1 LAST Q_TITLE CPU0 PCIE G2/G3
J 0
(-9425 125);
DISPLAY 2.446809 (-9425 125);
PAINT GREEN (-9425 125);
FORCEPROP 2 LAST PAGE_BORDER TRUE
J 0
(-7990 5350);
DISPLAY 0.638298 (-7990 5350);
PAINT PINK (-7990 5350);
DISPLAY INVISIBLE (-7990 5350);
FORCEPROP 1 LAST CDS_LMAN_SYM_OUTLINE -9475,6775,100,-125
J 0
(-100 100);
DISPLAY 0.468085 (-100 100);
PAINT GREEN (-100 100);
DISPLAY INVISIBLE (-100 100);
FORCEPROP 2 LAST CDS_LIB pure_quanta
J 0
(-100 100);
DISPLAY INVISIBLE (-100 100);
FORCEPROP 2 LAST CDS_XR_PAGE_TITLE CR-23 : @T6G_MB_LIB.T6G(SCH_1):PAGE23
J 0
(-7990 5350);
DISPLAY 0.638298 (-7990 5350);
PAINT PINK (-7990 5350);
DISPLAY INVISIBLE (-7990 5350);
FORCEPROP 1 LAST Q_DEPT BU9
J 1
(-3863 149);
DISPLAY 1.957447 (-3863 149);
PAINT GREEN (-3863 149);
DISPLAY INVISIBLE (-3863 149);
FORCEPROP 1 LAST COMMENT_BODY TRUE
J 0
(-88 87);
DISPLAY 0.978723 (-88 87);
PAINT GREEN (-88 87);
DISPLAY INVISIBLE (-88 87);
WIRE 17 -1 (-3025 3175)(-3025 2975);
WIRE 17 -1 (-3025 3175)(-2000 3175);
FORCEPROP 2 LAST SIG_NAME P5E_CPU0_G3_TX_DP<15:0>
J 0
(-2910 3185);
DISPLAY 0.489362 (-2910 3185);
WIRE 17 -1 (-2875 3125)(-2875 2925);
WIRE 17 -1 (-2875 3125)(-2000 3125);
FORCEPROP 2 LAST SIG_NAME P5E_CPU0_G3_TX_DN<15:0>
J 0
(-2910 3135);
DISPLAY 0.489362 (-2910 3135);
WIRE 17 -1 (-2875 2925)(-2875 2825);
WIRE 17 -1 (-2875 2825)(-2875 2725);
WIRE 17 -1 (-2875 2725)(-2875 2625);
WIRE 17 -1 (-2875 2625)(-2875 2525);
WIRE 17 -1 (-2875 2525)(-2875 2425);
WIRE 17 -1 (-2875 2425)(-2875 2325);
WIRE 17 -1 (-2875 2325)(-2875 2225);
WIRE 17 -1 (-3025 2675)(-3025 2575);
WIRE 17 -1 (-3025 2775)(-3025 2675);
WIRE 17 -1 (-3025 2575)(-3025 2475);
WIRE 17 -1 (-3025 2475)(-3025 2375);
WIRE 17 -1 (-3025 2875)(-3025 2775);
WIRE 17 -1 (-3025 2975)(-3025 2875);
WIRE 17 -1 (-3025 2375)(-3025 2275);
WIRE 17 -1 (-3025 2275)(-3025 2175);
WIRE 17 -1 (-2875 2225)(-2875 2125);
WIRE 17 -1 (-3025 2175)(-3025 2075);
WIRE 17 -1 (-3025 2075)(-3025 1975);
WIRE 17 -1 (-3025 1975)(-3025 1875);
WIRE 17 -1 (-3025 1875)(-3025 1775);
WIRE 17 -1 (-2875 2125)(-2875 2025);
WIRE 17 -1 (-2875 2025)(-2875 1925);
WIRE 17 -1 (-2875 1925)(-2875 1825);
WIRE 17 -1 (-2875 1825)(-2875 1725);
WIRE 17 -1 (-2875 1725)(-2875 1625);
WIRE 17 -1 (-2875 1625)(-2875 1525);
WIRE 17 -1 (-2875 1525)(-2875 1425);
WIRE 17 -1 (-3025 1775)(-3025 1675);
WIRE 17 -1 (-3025 1675)(-3025 1575);
WIRE 17 -1 (-3025 1575)(-3025 1475);
WIRE 17 -1 (-6550 2075)(-6550 2175);
WIRE 17 -1 (-6550 1975)(-6550 2075);
WIRE 17 -1 (-6550 2175)(-6550 2275);
WIRE 17 -1 (-6550 2275)(-6550 2375);
WIRE 17 -1 (-6550 1875)(-6550 1975);
WIRE 17 -1 (-6550 1775)(-6550 1875);
WIRE 17 -1 (-6550 2375)(-6550 2475);
WIRE 17 -1 (-6550 2475)(-6550 2575);
WIRE 17 -1 (-6550 1675)(-6550 1775);
WIRE 17 -1 (-6550 1575)(-6550 1675);
WIRE 17 -1 (-6550 2575)(-6550 2675);
WIRE 17 -1 (-6550 2675)(-6550 2775);
WIRE 17 -1 (-6550 1475)(-6550 1575);
WIRE 17 -1 (-6550 2775)(-6550 2875);
WIRE 17 -1 (-6550 2875)(-6550 2975);
WIRE 17 -1 (-6550 2975)(-6550 3175);
WIRE 17 -1 (-6550 3175)(-7650 3175);
WIRE 17 -1 (-2900 4400)(-2900 4300);
WIRE 17 -1 (-2900 4500)(-2900 4400);
WIRE 17 -1 (-2900 4600)(-2900 4500);
WIRE 17 -1 (-2900 4700)(-2900 4600);
WIRE 17 -1 (-2900 4800)(-2900 4700);
WIRE 17 -1 (-2900 4900)(-2900 4800);
WIRE 17 -1 (-2900 5000)(-2900 4900);
WIRE 17 -1 (-2900 5100)(-2900 5000);
WIRE 17 -1 (-2900 5200)(-2900 5100);
WIRE 17 -1 (-2900 5300)(-2900 5200);
WIRE 17 -1 (-2900 5400)(-2900 5300);
WIRE 17 -1 (-2900 5500)(-2900 5400);
WIRE 17 -1 (-2900 5600)(-2900 5500);
WIRE 17 -1 (-2900 5700)(-2900 5600);
WIRE 17 -1 (-2900 5800)(-2900 5700);
WIRE 17 -1 (-2900 6000)(-2900 5800);
WIRE 17 -1 (-2900 6000)(-1875 6000);
FORCEPROP 2 LAST SIG_NAME GMI_CPU0_G2_CPU1_G0_TX_DN<15:0>
J 0
(-2860 6010);
DISPLAY 0.489362 (-2860 6010);
WIRE 17 -1 (-6725 4700)(-6725 4800);
WIRE 17 -1 (-6725 4600)(-6725 4700);
WIRE 17 -1 (-6725 4800)(-6725 4900);
WIRE 17 -1 (-6725 4900)(-6725 5000);
WIRE 17 -1 (-6725 4500)(-6725 4600);
WIRE 17 -1 (-6725 4400)(-6725 4500);
WIRE 17 -1 (-6725 5000)(-6725 5100);
WIRE 17 -1 (-6725 5100)(-6725 5200);
WIRE 17 -1 (-6725 4300)(-6725 4400);
WIRE 17 -1 (-6725 5200)(-6725 5300);
WIRE 17 -1 (-6725 5300)(-6725 5400);
WIRE 17 -1 (-6725 5400)(-6725 5500);
WIRE 17 -1 (-6725 5500)(-6725 5600);
WIRE 17 -1 (-6725 5600)(-6725 5700);
WIRE 17 -1 (-6725 5700)(-6725 5800);
WIRE 17 -1 (-6725 5800)(-6725 6000);
WIRE 17 -1 (-6725 6000)(-7675 6000);
FORCEPROP 2 LAST SIG_NAME GMI_CPU1_G0_CPU0_G2_TX_DN<15:0>
J 0
(-7635 6010);
DISPLAY 0.489362 (-7635 6010);
WIRE 17 -1 (-6575 4750)(-6575 4850);
WIRE 17 -1 (-6575 4650)(-6575 4750);
WIRE 17 -1 (-6575 4850)(-6575 4950);
WIRE 17 -1 (-6575 4950)(-6575 5050);
WIRE 17 -1 (-6575 4550)(-6575 4650);
WIRE 17 -1 (-6575 4450)(-6575 4550);
WIRE 17 -1 (-6575 5050)(-6575 5150);
WIRE 17 -1 (-6575 5150)(-6575 5250);
WIRE 17 -1 (-6575 4350)(-6575 4450);
WIRE 17 -1 (-6575 5250)(-6575 5350);
WIRE 17 -1 (-6575 5350)(-6575 5450);
WIRE 17 -1 (-6575 5450)(-6575 5550);
WIRE 17 -1 (-6575 5550)(-6575 5650);
WIRE 17 -1 (-6575 5650)(-6575 5750);
WIRE 17 -1 (-6575 5750)(-6575 5850);
WIRE 17 -1 (-6575 5850)(-6575 6050);
WIRE 17 -1 (-6575 6050)(-7675 6050);
FORCEPROP 2 LAST SIG_NAME GMI_CPU1_G0_CPU0_G2_TX_DP<15:0>
J 0
(-7635 6060);
DISPLAY 0.489362 (-7635 6060);
WIRE 17 -1 (-6700 2525)(-6700 2625);
WIRE 17 -1 (-6700 2425)(-6700 2525);
WIRE 17 -1 (-6700 2625)(-6700 2725);
WIRE 17 -1 (-6700 2725)(-6700 2825);
WIRE 17 -1 (-6700 2325)(-6700 2425);
WIRE 17 -1 (-6700 2225)(-6700 2325);
WIRE 17 -1 (-6700 2825)(-6700 2925);
WIRE 17 -1 (-6700 2925)(-6700 3125);
WIRE 17 -1 (-6700 2125)(-6700 2225);
WIRE 17 -1 (-6700 2025)(-6700 2125);
WIRE 17 -1 (-6700 3125)(-7650 3125);
WIRE 17 -1 (-6700 1925)(-6700 2025);
WIRE 17 -1 (-6700 1825)(-6700 1925);
WIRE 17 -1 (-6700 1725)(-6700 1825);
WIRE 17 -1 (-6700 1625)(-6700 1725);
WIRE 17 -1 (-6700 1525)(-6700 1625);
WIRE 17 -1 (-6700 1425)(-6700 1525);
WIRE 17 -1 (-3050 5850)(-3050 5750);
WIRE 17 -1 (-3050 6050)(-3050 5850);
WIRE 17 -1 (-3050 5750)(-3050 5650);
WIRE 17 -1 (-3050 5650)(-3050 5550);
WIRE 17 -1 (-3050 6050)(-1875 6050);
FORCEPROP 2 LAST SIG_NAME GMI_CPU0_G2_CPU1_G0_TX_DP<15:0>
J 0
(-2860 6060);
DISPLAY 0.489362 (-2860 6060);
WIRE 17 -1 (-3050 5550)(-3050 5450);
WIRE 17 -1 (-3050 5450)(-3050 5350);
WIRE 17 -1 (-3050 5350)(-3050 5250);
WIRE 17 -1 (-3050 5250)(-3050 5150);
WIRE 17 -1 (-3050 5150)(-3050 5050);
WIRE 17 -1 (-3050 5050)(-3050 4950);
WIRE 17 -1 (-3050 4950)(-3050 4850);
WIRE 17 -1 (-3050 4850)(-3050 4750);
WIRE 17 -1 (-3050 4750)(-3050 4650);
WIRE 17 -1 (-3050 4650)(-3050 4550);
WIRE 17 -1 (-3050 4550)(-3050 4450);
WIRE 17 -1 (-3050 4450)(-3050 4350);
WIRE 16 -1 (-3500 2700)(-2975 2700);
WIRE 16 -1 (-3500 2650)(-3125 2650);
WIRE 16 -1 (-6625 5275)(-6025 5275);
WIRE 16 -1 (-6475 5225)(-6025 5225);
WIRE 16 -1 (-6625 5175)(-6025 5175);
WIRE 16 -1 (-6475 5125)(-6025 5125);
WIRE 16 -1 (-6625 5075)(-6025 5075);
WIRE 16 -1 (-6475 5025)(-6025 5025);
WIRE 16 -1 (-6625 4975)(-6025 4975);
WIRE 16 -1 (-6475 4925)(-6025 4925);
WIRE 16 -1 (-6625 4875)(-6025 4875);
WIRE 16 -1 (-6475 4725)(-6025 4725);
WIRE 16 -1 (-6625 4675)(-6025 4675);
WIRE 16 -1 (-6475 4625)(-6025 4625);
WIRE 16 -1 (-6625 4575)(-6025 4575);
WIRE 16 -1 (-6475 4525)(-6025 4525);
WIRE 16 -1 (-6450 2250)(-6000 2250);
WIRE 16 -1 (-6600 2200)(-6000 2200);
WIRE 16 -1 (-6450 2050)(-6000 2050);
WIRE 16 -1 (-6450 1750)(-6000 1750);
WIRE 16 -1 (-6450 1650)(-6000 1650);
WIRE 16 -1 (-6600 1700)(-6000 1700);
WIRE 16 -1 (-6600 1600)(-6000 1600);
WIRE 16 -1 (-6450 1550)(-6000 1550);
WIRE 16 -1 (-6600 1500)(-6000 1500);
WIRE 16 -1 (-6450 1450)(-6000 1450);
WIRE 16 -1 (-6600 1400)(-6000 1400);
WIRE 16 -1 (-6450 1950)(-6000 1950);
WIRE 16 -1 (-6600 1900)(-6000 1900);
WIRE 16 -1 (-6450 1850)(-6000 1850);
WIRE 16 -1 (-6625 5375)(-6025 5375);
WIRE 16 -1 (-6625 5475)(-6025 5475);
WIRE 16 -1 (-6475 5325)(-6025 5325);
WIRE 16 -1 (-6625 5575)(-6025 5575);
WIRE 16 -1 (-6475 5425)(-6025 5425);
WIRE 16 -1 (-6625 5675)(-6025 5675);
WIRE 16 -1 (-6475 5525)(-6025 5525);
WIRE 16 -1 (-6625 5775)(-6025 5775);
WIRE 16 -1 (-6475 5625)(-6025 5625);
WIRE 16 -1 (-6475 5725)(-6025 5725);
WIRE 16 -1 (-6475 5825)(-6025 5825);
WIRE 16 -1 (-6625 4275)(-6025 4275);
WIRE 16 -1 (-6475 4325)(-6025 4325);
WIRE 16 -1 (-6625 4475)(-6025 4475);
WIRE 16 -1 (-6625 4375)(-6025 4375);
WIRE 16 -1 (-6475 4425)(-6025 4425);
WIRE 16 -1 (-3500 1450)(-3125 1450);
WIRE 16 -1 (-3500 1750)(-3125 1750);
WIRE 16 -1 (-3500 1550)(-3125 1550);
WIRE 16 -1 (-3500 1850)(-3125 1850);
WIRE 16 -1 (-3500 1650)(-3125 1650);
WIRE 16 -1 (-3500 2000)(-2975 2000);
WIRE 16 -1 (-3500 1600)(-2975 1600);
WIRE 16 -1 (-3500 1700)(-2975 1700);
WIRE 16 -1 (-3500 1400)(-2975 1400);
WIRE 16 -1 (-3500 1800)(-2975 1800);
WIRE 16 -1 (-3500 1500)(-2975 1500);
WIRE 16 -1 (-3500 2150)(-3125 2150);
WIRE 16 -1 (-3500 2100)(-2975 2100);
WIRE 16 -1 (-3525 4325)(-3150 4325);
WIRE 16 -1 (-3525 4525)(-3150 4525);
WIRE 16 -1 (-3150 4425)(-3525 4425);
WIRE 16 -1 (-3525 4725)(-3150 4725);
WIRE 16 -1 (-3525 4925)(-3150 4925);
WIRE 16 -1 (-3525 4625)(-3150 4625);
WIRE 16 -1 (-3525 4825)(-3150 4825);
WIRE 16 -1 (-3525 5025)(-3150 5025);
WIRE 16 -1 (-3525 5125)(-3150 5125);
WIRE 16 -1 (-3525 5225)(-3150 5225);
WIRE 16 -1 (-3525 5325)(-3150 5325);
WIRE 16 -1 (-3525 5425)(-3150 5425);
WIRE 16 -1 (-3525 5525)(-3150 5525);
WIRE 16 -1 (-3525 5625)(-3150 5625);
WIRE 16 -1 (-3525 5825)(-3150 5825);
WIRE 16 -1 (-3525 5725)(-3150 5725);
WIRE 16 -1 (-3525 5075)(-3000 5075);
WIRE 16 -1 (-3525 5175)(-3000 5175);
WIRE 16 -1 (-3525 5275)(-3000 5275);
WIRE 16 -1 (-3525 5375)(-3000 5375);
WIRE 16 -1 (-3525 5475)(-3000 5475);
WIRE 16 -1 (-3525 5575)(-3000 5575);
WIRE 16 -1 (-3525 5675)(-3000 5675);
WIRE 16 -1 (-3525 5775)(-3000 5775);
WIRE 16 -1 (-3525 4475)(-3000 4475);
WIRE 16 -1 (-3525 4675)(-3000 4675);
WIRE 16 -1 (-3525 4875)(-3000 4875);
WIRE 16 -1 (-3525 4375)(-3000 4375);
WIRE 16 -1 (-3525 4575)(-3000 4575);
WIRE 16 -1 (-3525 4775)(-3000 4775);
WIRE 16 -1 (-3525 4975)(-3000 4975);
WIRE 16 -1 (-6600 1800)(-6000 1800);
WIRE 16 -1 (-6600 2000)(-6000 2000);
WIRE 16 -1 (-6600 2100)(-6000 2100);
WIRE 16 -1 (-6600 2900)(-6000 2900);
WIRE 16 -1 (-6450 2850)(-6000 2850);
WIRE 16 -1 (-6600 2800)(-6000 2800);
WIRE 16 -1 (-6450 2750)(-6000 2750);
WIRE 16 -1 (-6600 2700)(-6000 2700);
WIRE 16 -1 (-6450 2650)(-6000 2650);
WIRE 16 -1 (-6600 2600)(-6000 2600);
WIRE 16 -1 (-6450 2350)(-6000 2350);
WIRE 16 -1 (-6600 2300)(-6000 2300);
WIRE 16 -1 (-6450 2950)(-6000 2950);
WIRE 16 -1 (-6600 2400)(-6000 2400);
WIRE 16 -1 (-6450 2550)(-6000 2550);
WIRE 16 -1 (-6600 2500)(-6000 2500);
WIRE 16 -1 (-6450 2450)(-6000 2450);
WIRE 16 -1 (-3500 2850)(-3125 2850);
WIRE 16 -1 (-6475 4825)(-6025 4825);
WIRE 16 -1 (-6625 4775)(-6025 4775);
WIRE 16 -1 (-3525 4275)(-3000 4275);
WIRE 16 -1 (-3500 2050)(-3125 2050);
WIRE 16 -1 (-3500 2250)(-3125 2250);
WIRE 16 -1 (-3500 2750)(-3125 2750);
WIRE 16 -1 (-3500 2200)(-2975 2200);
WIRE 16 -1 (-6450 2150)(-6000 2150);
WIRE 16 -1 (-3500 1950)(-3125 1950);
WIRE 16 -1 (-3500 1900)(-2975 1900);
WIRE 16 -1 (-3500 2300)(-2975 2300);
WIRE 16 -1 (-3500 2450)(-3125 2450);
WIRE 16 -1 (-3500 2400)(-2975 2400);
WIRE 16 -1 (-3500 2350)(-3125 2350);
WIRE 16 -1 (-3500 2500)(-2975 2500);
WIRE 16 -1 (-3500 2550)(-3125 2550);
WIRE 16 -1 (-3500 2600)(-2975 2600);
WIRE 16 -1 (-3500 2800)(-2975 2800);
WIRE 16 -1 (-3500 2900)(-2975 2900);
WIRE 16 -1 (-3500 2950)(-3125 2950);
FORCENOTE
CPU0 G3[15:0] TO OCP SLOT#0
(-2550 2325) 0;
DISPLAY LEFT (-2550 2325);
DISPLAY 1.595745 (-2550 2325);
QUIT
